FILE_TYPE = MACRO_DRAWING;
SET COLOR_WIRE YELLOW;
SET COLOR_PROP ORANGE;
SET COLOR_DOT WHITE;
SET COLOR_ARC YELLOW;
SET COLOR_BODY GREEN;
SET COLOR_NOTE PURPLE;
SET PROP_DISPLAY VALUE;
SET PAGE_NUMBER P166;
FORCEADD OFFPAGE..1
(-2850 1625);
FORCEPROP 2 LAST $XR0 31 
J 0
(-3071 1625);
DISPLAY 0.638298 (-3071 1625);
PAINT MONO (-3071 1625);
FORCEPROP 2 LAST CDS_LIB standard
J 0
(-2850 1625);
DISPLAY INVISIBLE (-2850 1625);
FORCEPROP 1 LAST OFFPAGE TRUE
J 0
(-2525 1500);
DISPLAY 0.872340 (-2525 1500);
DISPLAY INVISIBLE (-2525 1500);
FORCEPROP 1 LAST COMMENT_BODY TRUE
J 0
(-2725 1525);
DISPLAY 0.872340 (-2725 1525);
PAINT GREEN (-2725 1525);
DISPLAY INVISIBLE (-2725 1525);
FORCEPROP 2 LAST PATH I209
J 0
(-3100 1675);
DISPLAY 1.021277 (-3100 1675);
DISPLAY INVISIBLE (-3100 1675);
FORCEADD OFFPAGE..1
(-2850 1575);
FORCEPROP 2 LAST $XR0 31 
J 0
(-3071 1575);
DISPLAY 0.638298 (-3071 1575);
PAINT MONO (-3071 1575);
FORCEPROP 2 LAST CDS_LIB standard
J 0
(-2850 1575);
DISPLAY INVISIBLE (-2850 1575);
FORCEPROP 1 LAST OFFPAGE TRUE
J 0
(-2525 1450);
DISPLAY 0.872340 (-2525 1450);
DISPLAY INVISIBLE (-2525 1450);
FORCEPROP 1 LAST COMMENT_BODY TRUE
J 0
(-2725 1475);
DISPLAY 0.872340 (-2725 1475);
PAINT GREEN (-2725 1475);
DISPLAY INVISIBLE (-2725 1475);
FORCEPROP 2 LAST PATH I210
J 0
(-3100 1625);
DISPLAY 1.021277 (-3100 1625);
DISPLAY INVISIBLE (-3100 1625);
FORCEADD OFFPAGE..1
(-2850 3550);
FORCEPROP 2 LAST $XR0 31 
J 0
(-3071 3550);
DISPLAY 0.638298 (-3071 3550);
PAINT MONO (-3071 3550);
FORCEPROP 2 LAST CDS_LIB standard
J 0
(-2850 3550);
DISPLAY INVISIBLE (-2850 3550);
FORCEPROP 1 LAST OFFPAGE TRUE
J 0
(-2525 3425);
DISPLAY 0.872340 (-2525 3425);
DISPLAY INVISIBLE (-2525 3425);
FORCEPROP 1 LAST COMMENT_BODY TRUE
J 0
(-2725 3450);
DISPLAY 0.872340 (-2725 3450);
PAINT GREEN (-2725 3450);
DISPLAY INVISIBLE (-2725 3450);
FORCEPROP 2 LAST PATH I211
J 0
(-3100 3600);
DISPLAY 1.021277 (-3100 3600);
DISPLAY INVISIBLE (-3100 3600);
FORCEADD OFFPAGE..1
(-2850 3600);
FORCEPROP 2 LAST $XR0 31 
J 0
(-3071 3600);
DISPLAY 0.638298 (-3071 3600);
PAINT MONO (-3071 3600);
FORCEPROP 2 LAST CDS_LIB standard
J 0
(-2850 3600);
DISPLAY INVISIBLE (-2850 3600);
FORCEPROP 1 LAST OFFPAGE TRUE
J 0
(-2525 3475);
DISPLAY 0.872340 (-2525 3475);
DISPLAY INVISIBLE (-2525 3475);
FORCEPROP 1 LAST COMMENT_BODY TRUE
J 0
(-2725 3500);
DISPLAY 0.872340 (-2725 3500);
PAINT GREEN (-2725 3500);
DISPLAY INVISIBLE (-2725 3500);
FORCEPROP 2 LAST PATH I212
J 0
(-3100 3650);
DISPLAY 1.021277 (-3100 3650);
DISPLAY INVISIBLE (-3100 3650);
FORCEADD TAP..1
R 2
(-1900 150);
FORCEPROP 3 LASTPIN (-1850 150) SIG_NAME P5E_CPU0_PE4_TX_DP<0>
J 0
(-1840 160);
DISPLAY 0.659574 (-1840 160);
PAINT MONO (-1840 160);
DISPLAY INVISIBLE (-1840 160);
FORCEPROP 1 LASTPIN (-1850 150) BN 0
J 2
(-1838 158);
DISPLAY 0.680851 (-1838 158);
PAINT GREEN (-1838 158);
FORCEPROP 2 LAST CDS_LIB standard
J 0
(-1900 150);
DISPLAY INVISIBLE (-1900 150);
FORCEPROP 1 LAST BODY_TYPE PLUMBING
J 2
(-1900 200);
DISPLAY 0.872340 (-1900 200);
PAINT GREEN (-1900 200);
DISPLAY INVISIBLE (-1900 200);
FORCEPROP 1 LAST HDL_TAP TRUE
J 2
(-2225 25);
DISPLAY 0.872340 (-2225 25);
DISPLAY INVISIBLE (-2225 25);
FORCEPROP 1 LAST PATH I213
J 2
(-1898 150);
DISPLAY 0.872340 (-1898 150);
PAINT GREEN (-1898 150);
DISPLAY INVISIBLE (-1898 150);
FORCEADD TAP..1
R 2
(-1900 350);
FORCEPROP 3 LASTPIN (-1850 350) SIG_NAME P5E_CPU0_PE4_TX_DP<1>
J 0
(-1840 360);
DISPLAY 0.659574 (-1840 360);
PAINT MONO (-1840 360);
DISPLAY INVISIBLE (-1840 360);
FORCEPROP 1 LASTPIN (-1850 350) BN 1
J 2
(-1838 358);
DISPLAY 0.680851 (-1838 358);
PAINT GREEN (-1838 358);
FORCEPROP 2 LAST CDS_LIB standard
J 0
(-1900 350);
DISPLAY INVISIBLE (-1900 350);
FORCEPROP 1 LAST BODY_TYPE PLUMBING
J 2
(-1900 400);
DISPLAY 0.872340 (-1900 400);
PAINT GREEN (-1900 400);
DISPLAY INVISIBLE (-1900 400);
FORCEPROP 1 LAST HDL_TAP TRUE
J 2
(-2225 225);
DISPLAY 0.872340 (-2225 225);
DISPLAY INVISIBLE (-2225 225);
FORCEPROP 1 LAST PATH I214
J 2
(-1898 350);
DISPLAY 0.872340 (-1898 350);
PAINT GREEN (-1898 350);
DISPLAY INVISIBLE (-1898 350);
FORCEADD TAP..1
R 2
(-1650 200);
FORCEPROP 3 LASTPIN (-1600 200) SIG_NAME P5E_CPU0_PE4_TX_DN<0>
J 0
(-1590 210);
DISPLAY 0.659574 (-1590 210);
PAINT MONO (-1590 210);
DISPLAY INVISIBLE (-1590 210);
FORCEPROP 1 LASTPIN (-1600 200) BN 0
J 2
(-1588 208);
DISPLAY 0.680851 (-1588 208);
PAINT GREEN (-1588 208);
FORCEPROP 2 LAST CDS_LIB standard
J 0
(-1650 200);
DISPLAY INVISIBLE (-1650 200);
FORCEPROP 1 LAST BODY_TYPE PLUMBING
J 2
(-1650 250);
DISPLAY 0.872340 (-1650 250);
PAINT GREEN (-1650 250);
DISPLAY INVISIBLE (-1650 250);
FORCEPROP 1 LAST HDL_TAP TRUE
J 2
(-1975 75);
DISPLAY 0.872340 (-1975 75);
DISPLAY INVISIBLE (-1975 75);
FORCEPROP 1 LAST PATH I215
J 2
(-1648 200);
DISPLAY 0.872340 (-1648 200);
PAINT GREEN (-1648 200);
DISPLAY INVISIBLE (-1648 200);
FORCEADD TAP..1
R 2
(-1650 400);
FORCEPROP 3 LASTPIN (-1600 400) SIG_NAME P5E_CPU0_PE4_TX_DN<1>
J 0
(-1590 410);
DISPLAY 0.659574 (-1590 410);
PAINT MONO (-1590 410);
DISPLAY INVISIBLE (-1590 410);
FORCEPROP 1 LASTPIN (-1600 400) BN 1
J 2
(-1588 408);
DISPLAY 0.680851 (-1588 408);
PAINT GREEN (-1588 408);
FORCEPROP 2 LAST CDS_LIB standard
J 0
(-1650 400);
DISPLAY INVISIBLE (-1650 400);
FORCEPROP 1 LAST BODY_TYPE PLUMBING
J 2
(-1650 450);
DISPLAY 0.872340 (-1650 450);
PAINT GREEN (-1650 450);
DISPLAY INVISIBLE (-1650 450);
FORCEPROP 1 LAST HDL_TAP TRUE
J 2
(-1975 275);
DISPLAY 0.872340 (-1975 275);
DISPLAY INVISIBLE (-1975 275);
FORCEPROP 1 LAST PATH I216
J 2
(-1648 400);
DISPLAY 0.872340 (-1648 400);
PAINT GREEN (-1648 400);
DISPLAY INVISIBLE (-1648 400);
FORCEADD TAP..1
R 2
(-1900 750);
FORCEPROP 3 LASTPIN (-1850 750) SIG_NAME P5E_CPU0_PE4_TX_DP<3>
J 0
(-1840 760);
DISPLAY 0.659574 (-1840 760);
PAINT MONO (-1840 760);
DISPLAY INVISIBLE (-1840 760);
FORCEPROP 1 LASTPIN (-1850 750) BN 3
J 2
(-1838 758);
DISPLAY 0.680851 (-1838 758);
PAINT GREEN (-1838 758);
FORCEPROP 2 LAST CDS_LIB standard
J 0
(-1900 750);
DISPLAY INVISIBLE (-1900 750);
FORCEPROP 1 LAST BODY_TYPE PLUMBING
J 2
(-1900 800);
DISPLAY 0.872340 (-1900 800);
PAINT GREEN (-1900 800);
DISPLAY INVISIBLE (-1900 800);
FORCEPROP 1 LAST HDL_TAP TRUE
J 2
(-2225 625);
DISPLAY 0.872340 (-2225 625);
DISPLAY INVISIBLE (-2225 625);
FORCEPROP 1 LAST PATH I217
J 2
(-1898 750);
DISPLAY 0.872340 (-1898 750);
PAINT GREEN (-1898 750);
DISPLAY INVISIBLE (-1898 750);
FORCEADD TAP..1
R 2
(-1900 550);
FORCEPROP 3 LASTPIN (-1850 550) SIG_NAME P5E_CPU0_PE4_TX_DP<2>
J 0
(-1840 560);
DISPLAY 0.659574 (-1840 560);
PAINT MONO (-1840 560);
DISPLAY INVISIBLE (-1840 560);
FORCEPROP 1 LASTPIN (-1850 550) BN 2
J 2
(-1838 558);
DISPLAY 0.680851 (-1838 558);
PAINT GREEN (-1838 558);
FORCEPROP 2 LAST CDS_LIB standard
J 0
(-1900 550);
DISPLAY INVISIBLE (-1900 550);
FORCEPROP 1 LAST BODY_TYPE PLUMBING
J 2
(-1900 600);
DISPLAY 0.872340 (-1900 600);
PAINT GREEN (-1900 600);
DISPLAY INVISIBLE (-1900 600);
FORCEPROP 1 LAST HDL_TAP TRUE
J 2
(-2225 425);
DISPLAY 0.872340 (-2225 425);
DISPLAY INVISIBLE (-2225 425);
FORCEPROP 1 LAST PATH I218
J 2
(-1898 550);
DISPLAY 0.872340 (-1898 550);
PAINT GREEN (-1898 550);
DISPLAY INVISIBLE (-1898 550);
FORCEADD TAP..1
R 2
(-1900 950);
FORCEPROP 3 LASTPIN (-1850 950) SIG_NAME P5E_CPU0_PE4_TX_DP<4>
J 0
(-1840 960);
DISPLAY 0.659574 (-1840 960);
PAINT MONO (-1840 960);
DISPLAY INVISIBLE (-1840 960);
FORCEPROP 1 LASTPIN (-1850 950) BN 4
J 2
(-1838 958);
DISPLAY 0.680851 (-1838 958);
PAINT GREEN (-1838 958);
FORCEPROP 2 LAST CDS_LIB standard
J 0
(-1900 950);
DISPLAY INVISIBLE (-1900 950);
FORCEPROP 1 LAST BODY_TYPE PLUMBING
J 2
(-1900 1000);
DISPLAY 0.872340 (-1900 1000);
PAINT GREEN (-1900 1000);
DISPLAY INVISIBLE (-1900 1000);
FORCEPROP 1 LAST HDL_TAP TRUE
J 2
(-2225 825);
DISPLAY 0.872340 (-2225 825);
DISPLAY INVISIBLE (-2225 825);
FORCEPROP 1 LAST PATH I219
J 2
(-1898 950);
DISPLAY 0.872340 (-1898 950);
PAINT GREEN (-1898 950);
DISPLAY INVISIBLE (-1898 950);
FORCEADD TAP..1
R 2
(-1650 600);
FORCEPROP 3 LASTPIN (-1600 600) SIG_NAME P5E_CPU0_PE4_TX_DN<2>
J 0
(-1590 610);
DISPLAY 0.659574 (-1590 610);
PAINT MONO (-1590 610);
DISPLAY INVISIBLE (-1590 610);
FORCEPROP 1 LASTPIN (-1600 600) BN 2
J 2
(-1588 608);
DISPLAY 0.680851 (-1588 608);
PAINT GREEN (-1588 608);
FORCEPROP 2 LAST CDS_LIB standard
J 0
(-1650 600);
DISPLAY INVISIBLE (-1650 600);
FORCEPROP 1 LAST BODY_TYPE PLUMBING
J 2
(-1650 650);
DISPLAY 0.872340 (-1650 650);
PAINT GREEN (-1650 650);
DISPLAY INVISIBLE (-1650 650);
FORCEPROP 1 LAST HDL_TAP TRUE
J 2
(-1975 475);
DISPLAY 0.872340 (-1975 475);
DISPLAY INVISIBLE (-1975 475);
FORCEPROP 1 LAST PATH I220
J 2
(-1648 600);
DISPLAY 0.872340 (-1648 600);
PAINT GREEN (-1648 600);
DISPLAY INVISIBLE (-1648 600);
FORCEADD TAP..1
R 2
(-1650 800);
FORCEPROP 3 LASTPIN (-1600 800) SIG_NAME P5E_CPU0_PE4_TX_DN<3>
J 0
(-1590 810);
DISPLAY 0.659574 (-1590 810);
PAINT MONO (-1590 810);
DISPLAY INVISIBLE (-1590 810);
FORCEPROP 1 LASTPIN (-1600 800) BN 3
J 2
(-1588 808);
DISPLAY 0.680851 (-1588 808);
PAINT GREEN (-1588 808);
FORCEPROP 2 LAST CDS_LIB standard
J 0
(-1650 800);
DISPLAY INVISIBLE (-1650 800);
FORCEPROP 1 LAST BODY_TYPE PLUMBING
J 2
(-1650 850);
DISPLAY 0.872340 (-1650 850);
PAINT GREEN (-1650 850);
DISPLAY INVISIBLE (-1650 850);
FORCEPROP 1 LAST HDL_TAP TRUE
J 2
(-1975 675);
DISPLAY 0.872340 (-1975 675);
DISPLAY INVISIBLE (-1975 675);
FORCEPROP 1 LAST PATH I221
J 2
(-1648 800);
DISPLAY 0.872340 (-1648 800);
PAINT GREEN (-1648 800);
DISPLAY INVISIBLE (-1648 800);
FORCEADD TAP..1
R 2
(-1650 1000);
FORCEPROP 3 LASTPIN (-1600 1000) SIG_NAME P5E_CPU0_PE4_TX_DN<4>
J 0
(-1590 1010);
DISPLAY 0.659574 (-1590 1010);
PAINT MONO (-1590 1010);
DISPLAY INVISIBLE (-1590 1010);
FORCEPROP 1 LASTPIN (-1600 1000) BN 4
J 2
(-1588 1008);
DISPLAY 0.680851 (-1588 1008);
PAINT GREEN (-1588 1008);
FORCEPROP 2 LAST CDS_LIB standard
J 0
(-1650 1000);
DISPLAY INVISIBLE (-1650 1000);
FORCEPROP 1 LAST BODY_TYPE PLUMBING
J 2
(-1650 1050);
DISPLAY 0.872340 (-1650 1050);
PAINT GREEN (-1650 1050);
DISPLAY INVISIBLE (-1650 1050);
FORCEPROP 1 LAST HDL_TAP TRUE
J 2
(-1975 875);
DISPLAY 0.872340 (-1975 875);
DISPLAY INVISIBLE (-1975 875);
FORCEPROP 1 LAST PATH I222
J 2
(-1648 1000);
DISPLAY 0.872340 (-1648 1000);
PAINT GREEN (-1648 1000);
DISPLAY INVISIBLE (-1648 1000);
FORCEADD TAP..1
R 2
(-1900 1150);
FORCEPROP 3 LASTPIN (-1850 1150) SIG_NAME P5E_CPU0_PE4_TX_DP<5>
J 0
(-1840 1160);
DISPLAY 0.659574 (-1840 1160);
PAINT MONO (-1840 1160);
DISPLAY INVISIBLE (-1840 1160);
FORCEPROP 1 LASTPIN (-1850 1150) BN 5
J 2
(-1838 1158);
DISPLAY 0.680851 (-1838 1158);
PAINT GREEN (-1838 1158);
FORCEPROP 2 LAST CDS_LIB standard
J 0
(-1900 1150);
DISPLAY INVISIBLE (-1900 1150);
FORCEPROP 1 LAST BODY_TYPE PLUMBING
J 2
(-1900 1200);
DISPLAY 0.872340 (-1900 1200);
PAINT GREEN (-1900 1200);
DISPLAY INVISIBLE (-1900 1200);
FORCEPROP 1 LAST HDL_TAP TRUE
J 2
(-2225 1025);
DISPLAY 0.872340 (-2225 1025);
DISPLAY INVISIBLE (-2225 1025);
FORCEPROP 1 LAST PATH I223
J 2
(-1898 1150);
DISPLAY 0.872340 (-1898 1150);
PAINT GREEN (-1898 1150);
DISPLAY INVISIBLE (-1898 1150);
FORCEADD TAP..1
R 2
(-1900 1350);
FORCEPROP 3 LASTPIN (-1850 1350) SIG_NAME P5E_CPU0_PE4_TX_DP<6>
J 0
(-1840 1360);
DISPLAY 0.659574 (-1840 1360);
PAINT MONO (-1840 1360);
DISPLAY INVISIBLE (-1840 1360);
FORCEPROP 1 LASTPIN (-1850 1350) BN 6
J 2
(-1838 1358);
DISPLAY 0.680851 (-1838 1358);
PAINT GREEN (-1838 1358);
FORCEPROP 2 LAST CDS_LIB standard
J 0
(-1900 1350);
DISPLAY INVISIBLE (-1900 1350);
FORCEPROP 1 LAST BODY_TYPE PLUMBING
J 2
(-1900 1400);
DISPLAY 0.872340 (-1900 1400);
PAINT GREEN (-1900 1400);
DISPLAY INVISIBLE (-1900 1400);
FORCEPROP 1 LAST HDL_TAP TRUE
J 2
(-2225 1225);
DISPLAY 0.872340 (-2225 1225);
DISPLAY INVISIBLE (-2225 1225);
FORCEPROP 1 LAST PATH I224
J 2
(-1898 1350);
DISPLAY 0.872340 (-1898 1350);
PAINT GREEN (-1898 1350);
DISPLAY INVISIBLE (-1898 1350);
FORCEADD TAP..1
R 2
(-1650 1200);
FORCEPROP 3 LASTPIN (-1600 1200) SIG_NAME P5E_CPU0_PE4_TX_DN<5>
J 0
(-1590 1210);
DISPLAY 0.659574 (-1590 1210);
PAINT MONO (-1590 1210);
DISPLAY INVISIBLE (-1590 1210);
FORCEPROP 1 LASTPIN (-1600 1200) BN 5
J 2
(-1588 1208);
DISPLAY 0.680851 (-1588 1208);
PAINT GREEN (-1588 1208);
FORCEPROP 2 LAST CDS_LIB standard
J 0
(-1650 1200);
DISPLAY INVISIBLE (-1650 1200);
FORCEPROP 1 LAST BODY_TYPE PLUMBING
J 2
(-1650 1250);
DISPLAY 0.872340 (-1650 1250);
PAINT GREEN (-1650 1250);
DISPLAY INVISIBLE (-1650 1250);
FORCEPROP 1 LAST HDL_TAP TRUE
J 2
(-1975 1075);
DISPLAY 0.872340 (-1975 1075);
DISPLAY INVISIBLE (-1975 1075);
FORCEPROP 1 LAST PATH I225
J 2
(-1648 1200);
DISPLAY 0.872340 (-1648 1200);
PAINT GREEN (-1648 1200);
DISPLAY INVISIBLE (-1648 1200);
FORCEADD TAP..1
R 2
(-1650 1400);
FORCEPROP 3 LASTPIN (-1600 1400) SIG_NAME P5E_CPU0_PE4_TX_DN<6>
J 0
(-1590 1410);
DISPLAY 0.659574 (-1590 1410);
PAINT MONO (-1590 1410);
DISPLAY INVISIBLE (-1590 1410);
FORCEPROP 1 LASTPIN (-1600 1400) BN 6
J 2
(-1588 1408);
DISPLAY 0.680851 (-1588 1408);
PAINT GREEN (-1588 1408);
FORCEPROP 2 LAST CDS_LIB standard
J 0
(-1650 1400);
DISPLAY INVISIBLE (-1650 1400);
FORCEPROP 1 LAST BODY_TYPE PLUMBING
J 2
(-1650 1450);
DISPLAY 0.872340 (-1650 1450);
PAINT GREEN (-1650 1450);
DISPLAY INVISIBLE (-1650 1450);
FORCEPROP 1 LAST HDL_TAP TRUE
J 2
(-1975 1275);
DISPLAY 0.872340 (-1975 1275);
DISPLAY INVISIBLE (-1975 1275);
FORCEPROP 1 LAST PATH I226
J 2
(-1648 1400);
DISPLAY 0.872340 (-1648 1400);
PAINT GREEN (-1648 1400);
DISPLAY INVISIBLE (-1648 1400);
FORCEADD TAP..1
R 2
(-1900 1550);
FORCEPROP 3 LASTPIN (-1850 1550) SIG_NAME P5E_CPU0_PE4_TX_DP<7>
J 0
(-1840 1560);
DISPLAY 0.659574 (-1840 1560);
PAINT MONO (-1840 1560);
DISPLAY INVISIBLE (-1840 1560);
FORCEPROP 1 LASTPIN (-1850 1550) BN 7
J 2
(-1838 1558);
DISPLAY 0.680851 (-1838 1558);
PAINT GREEN (-1838 1558);
FORCEPROP 2 LAST CDS_LIB standard
J 0
(-1900 1550);
DISPLAY INVISIBLE (-1900 1550);
FORCEPROP 1 LAST BODY_TYPE PLUMBING
J 2
(-1900 1600);
DISPLAY 0.872340 (-1900 1600);
PAINT GREEN (-1900 1600);
DISPLAY INVISIBLE (-1900 1600);
FORCEPROP 1 LAST HDL_TAP TRUE
J 2
(-2225 1425);
DISPLAY 0.872340 (-2225 1425);
DISPLAY INVISIBLE (-2225 1425);
FORCEPROP 1 LAST PATH I227
J 2
(-1898 1550);
DISPLAY 0.872340 (-1898 1550);
PAINT GREEN (-1898 1550);
DISPLAY INVISIBLE (-1898 1550);
FORCEADD TAP..1
R 2
(-1650 1600);
FORCEPROP 3 LASTPIN (-1600 1600) SIG_NAME P5E_CPU0_PE4_TX_DN<7>
J 0
(-1590 1610);
DISPLAY 0.659574 (-1590 1610);
PAINT MONO (-1590 1610);
DISPLAY INVISIBLE (-1590 1610);
FORCEPROP 1 LASTPIN (-1600 1600) BN 7
J 2
(-1588 1608);
DISPLAY 0.680851 (-1588 1608);
PAINT GREEN (-1588 1608);
FORCEPROP 2 LAST CDS_LIB standard
J 0
(-1650 1600);
DISPLAY INVISIBLE (-1650 1600);
FORCEPROP 1 LAST BODY_TYPE PLUMBING
J 2
(-1650 1650);
DISPLAY 0.872340 (-1650 1650);
PAINT GREEN (-1650 1650);
DISPLAY INVISIBLE (-1650 1650);
FORCEPROP 1 LAST HDL_TAP TRUE
J 2
(-1975 1475);
DISPLAY 0.872340 (-1975 1475);
DISPLAY INVISIBLE (-1975 1475);
FORCEPROP 1 LAST PATH I228
J 2
(-1648 1600);
DISPLAY 0.872340 (-1648 1600);
PAINT GREEN (-1648 1600);
DISPLAY INVISIBLE (-1648 1600);
FORCEADD Q_CAP_DIFFBUS..2
R 2
(-925 150);
FORCEPROP 1 LAST PART_NUMBER SP_CH4221MEE01
J 2
(-1041 238);
DISPLAY 0.574468 (-1041 238);
PAINT GREEN (-1041 238);
DISPLAY INVISIBLE (-1041 238);
FORCEPROP 2 LAST VALUE DIFF BUS_0.22UF
J 2
(-1075 150);
DISPLAY 0.553191 (-1075 150);
FORCEPROP 1 LAST $LOCATION C1579
J 2
(-675 175);
DISPLAY 0.723404 (-675 175);
PAINT GREEN (-675 175);
FORCEPROP 2 LASTPIN (-850 150) $PN 1
J 0
(-840 160);
DISPLAY 0.808511 (-840 160);
FORCEPROP 2 LASTPIN (-1000 150) $PN 2
J 2
(-1010 160);
DISPLAY 0.808511 (-1010 160);
FORCEPROP 1 LAST PIN_NAMES_ROTATE TRUE
J 2
(-925 150);
DISPLAY 0.489362 (-925 150);
PAINT GREEN (-925 150);
DISPLAY INVISIBLE (-925 150);
FORCEPROP 2 LAST CDS_LIB pure_quanta
J 2
(-925 150);
DISPLAY INVISIBLE (-925 150);
FORCEPROP 1 LAST CDS_LMAN_SYM_OUTLINE -25,50,25,-50
J 2
(-925 150);
DISPLAY 0.468085 (-925 150);
PAINT GREEN (-925 150);
DISPLAY INVISIBLE (-925 150);
FORCEPROP 2 LAST VOLTAGE 6.3V
J 2
(-1275 200);
DISPLAY 0.553191 (-1275 200);
DISPLAY INVISIBLE (-1275 200);
FORCEPROP 1 LAST MATERIAL X6S
J 2
(-916 229);
DISPLAY 0.574468 (-916 229);
PAINT GREEN (-916 229);
DISPLAY INVISIBLE (-916 229);
FORCEPROP 2 LAST PACK_TYPE C0201
J 2
(-1100 200);
DISPLAY 0.553191 (-1100 200);
DISPLAY INVISIBLE (-1100 200);
FORCEPROP 2 LAST TOLERANCE 20%
J 2
(-1000 200);
DISPLAY 0.553191 (-1000 200);
DISPLAY INVISIBLE (-1000 200);
FORCEPROP 1 LAST PATH I229
J 2
(-925 150);
DISPLAY 0.723404 (-925 150);
DISPLAY INVISIBLE (-925 150);
FORCEPROP 0 LAST CDS_LOCATION C1579
J 0
(-675 225);
DISPLAY 1.021277 (-675 225);
DISPLAY INVISIBLE (-675 225);
FORCEPROP 2 LAST $SEC 1
J 2
(-750 225);
DISPLAY 0.680851 (-750 225);
PAINT MONO (-750 225);
DISPLAY INVISIBLE (-750 225);
FORCEPROP 2 LAST CDS_SEC 1
J 2
(-750 225);
DISPLAY 0.680851 (-750 225);
DISPLAY INVISIBLE (-750 225);
FORCEADD Q_CAP_DIFFBUS..2
R 2
(-925 200);
FORCEPROP 1 LAST PART_NUMBER SP_CH4221MEE01
J 2
(-1041 288);
DISPLAY 0.574468 (-1041 288);
PAINT GREEN (-1041 288);
DISPLAY INVISIBLE (-1041 288);
FORCEPROP 2 LAST VALUE DIFF BUS_0.22UF
J 2
(-1075 200);
DISPLAY 0.553191 (-1075 200);
FORCEPROP 1 LAST $LOCATION C1578
J 2
(-675 225);
DISPLAY 0.723404 (-675 225);
PAINT GREEN (-675 225);
FORCEPROP 2 LASTPIN (-850 200) $PN 1
J 0
(-840 210);
DISPLAY 0.808511 (-840 210);
FORCEPROP 2 LASTPIN (-1000 200) $PN 2
J 2
(-1010 210);
DISPLAY 0.808511 (-1010 210);
FORCEPROP 1 LAST PIN_NAMES_ROTATE TRUE
J 2
(-925 200);
DISPLAY 0.489362 (-925 200);
PAINT GREEN (-925 200);
DISPLAY INVISIBLE (-925 200);
FORCEPROP 2 LAST CDS_LIB pure_quanta
J 2
(-925 200);
DISPLAY INVISIBLE (-925 200);
FORCEPROP 1 LAST CDS_LMAN_SYM_OUTLINE -25,50,25,-50
J 2
(-925 200);
DISPLAY 0.468085 (-925 200);
PAINT GREEN (-925 200);
DISPLAY INVISIBLE (-925 200);
FORCEPROP 2 LAST VOLTAGE 6.3V
J 2
(-1275 250);
DISPLAY 0.553191 (-1275 250);
DISPLAY INVISIBLE (-1275 250);
FORCEPROP 1 LAST MATERIAL X6S
J 2
(-916 279);
DISPLAY 0.574468 (-916 279);
PAINT GREEN (-916 279);
DISPLAY INVISIBLE (-916 279);
FORCEPROP 2 LAST PACK_TYPE C0201
J 2
(-1100 250);
DISPLAY 0.553191 (-1100 250);
DISPLAY INVISIBLE (-1100 250);
FORCEPROP 2 LAST TOLERANCE 20%
J 2
(-1000 250);
DISPLAY 0.553191 (-1000 250);
DISPLAY INVISIBLE (-1000 250);
FORCEPROP 1 LAST PATH I230
J 2
(-925 200);
DISPLAY 0.723404 (-925 200);
DISPLAY INVISIBLE (-925 200);
FORCEPROP 0 LAST CDS_LOCATION C1578
J 0
(-675 275);
DISPLAY 1.021277 (-675 275);
DISPLAY INVISIBLE (-675 275);
FORCEPROP 2 LAST $SEC 1
J 2
(-750 275);
DISPLAY 0.680851 (-750 275);
PAINT MONO (-750 275);
DISPLAY INVISIBLE (-750 275);
FORCEPROP 2 LAST CDS_SEC 1
J 2
(-750 275);
DISPLAY 0.680851 (-750 275);
DISPLAY INVISIBLE (-750 275);
FORCEADD Q_CAP_DIFFBUS..2
R 2
(-925 550);
FORCEPROP 1 LAST PART_NUMBER SP_CH4221MEE01
J 2
(-1041 638);
DISPLAY 0.574468 (-1041 638);
PAINT GREEN (-1041 638);
DISPLAY INVISIBLE (-1041 638);
FORCEPROP 2 LAST VALUE DIFF BUS_0.22UF
J 2
(-1075 550);
DISPLAY 0.553191 (-1075 550);
FORCEPROP 1 LAST $LOCATION C1575
J 2
(-675 575);
DISPLAY 0.723404 (-675 575);
PAINT GREEN (-675 575);
FORCEPROP 2 LASTPIN (-850 550) $PN 1
J 0
(-840 560);
DISPLAY 0.808511 (-840 560);
FORCEPROP 2 LASTPIN (-1000 550) $PN 2
J 2
(-1010 560);
DISPLAY 0.808511 (-1010 560);
FORCEPROP 1 LAST PIN_NAMES_ROTATE TRUE
J 2
(-925 550);
DISPLAY 0.489362 (-925 550);
PAINT GREEN (-925 550);
DISPLAY INVISIBLE (-925 550);
FORCEPROP 2 LAST CDS_LIB pure_quanta
J 2
(-925 550);
DISPLAY INVISIBLE (-925 550);
FORCEPROP 1 LAST CDS_LMAN_SYM_OUTLINE -25,50,25,-50
J 2
(-925 550);
DISPLAY 0.468085 (-925 550);
PAINT GREEN (-925 550);
DISPLAY INVISIBLE (-925 550);
FORCEPROP 2 LAST VOLTAGE 6.3V
J 2
(-1275 600);
DISPLAY 0.553191 (-1275 600);
DISPLAY INVISIBLE (-1275 600);
FORCEPROP 1 LAST MATERIAL X6S
J 2
(-916 629);
DISPLAY 0.574468 (-916 629);
PAINT GREEN (-916 629);
DISPLAY INVISIBLE (-916 629);
FORCEPROP 2 LAST PACK_TYPE C0201
J 2
(-1100 600);
DISPLAY 0.553191 (-1100 600);
DISPLAY INVISIBLE (-1100 600);
FORCEPROP 2 LAST TOLERANCE 20%
J 2
(-1000 600);
DISPLAY 0.553191 (-1000 600);
DISPLAY INVISIBLE (-1000 600);
FORCEPROP 1 LAST PATH I231
J 2
(-925 550);
DISPLAY 0.723404 (-925 550);
DISPLAY INVISIBLE (-925 550);
FORCEPROP 0 LAST CDS_LOCATION C1575
J 0
(-675 625);
DISPLAY 1.021277 (-675 625);
DISPLAY INVISIBLE (-675 625);
FORCEPROP 2 LAST $SEC 1
J 2
(-750 625);
DISPLAY 0.680851 (-750 625);
PAINT MONO (-750 625);
DISPLAY INVISIBLE (-750 625);
FORCEPROP 2 LAST CDS_SEC 1
J 2
(-750 625);
DISPLAY 0.680851 (-750 625);
DISPLAY INVISIBLE (-750 625);
FORCEADD Q_CAP_DIFFBUS..2
R 2
(-925 600);
FORCEPROP 1 LAST PART_NUMBER SP_CH4221MEE01
J 2
(-1041 688);
DISPLAY 0.574468 (-1041 688);
PAINT GREEN (-1041 688);
DISPLAY INVISIBLE (-1041 688);
FORCEPROP 2 LAST VALUE DIFF BUS_0.22UF
J 2
(-1075 600);
DISPLAY 0.553191 (-1075 600);
FORCEPROP 1 LAST $LOCATION C1574
J 2
(-675 625);
DISPLAY 0.723404 (-675 625);
PAINT GREEN (-675 625);
FORCEPROP 2 LASTPIN (-850 600) $PN 1
J 0
(-840 610);
DISPLAY 0.808511 (-840 610);
FORCEPROP 2 LASTPIN (-1000 600) $PN 2
J 2
(-1010 610);
DISPLAY 0.808511 (-1010 610);
FORCEPROP 1 LAST PIN_NAMES_ROTATE TRUE
J 2
(-925 600);
DISPLAY 0.489362 (-925 600);
PAINT GREEN (-925 600);
DISPLAY INVISIBLE (-925 600);
FORCEPROP 2 LAST CDS_LIB pure_quanta
J 2
(-925 600);
DISPLAY INVISIBLE (-925 600);
FORCEPROP 1 LAST CDS_LMAN_SYM_OUTLINE -25,50,25,-50
J 2
(-925 600);
DISPLAY 0.468085 (-925 600);
PAINT GREEN (-925 600);
DISPLAY INVISIBLE (-925 600);
FORCEPROP 2 LAST VOLTAGE 6.3V
J 2
(-1275 650);
DISPLAY 0.553191 (-1275 650);
DISPLAY INVISIBLE (-1275 650);
FORCEPROP 1 LAST MATERIAL X6S
J 2
(-916 679);
DISPLAY 0.574468 (-916 679);
PAINT GREEN (-916 679);
DISPLAY INVISIBLE (-916 679);
FORCEPROP 2 LAST PACK_TYPE C0201
J 2
(-1100 650);
DISPLAY 0.553191 (-1100 650);
DISPLAY INVISIBLE (-1100 650);
FORCEPROP 2 LAST TOLERANCE 20%
J 2
(-1000 650);
DISPLAY 0.553191 (-1000 650);
DISPLAY INVISIBLE (-1000 650);
FORCEPROP 1 LAST PATH I232
J 2
(-925 600);
DISPLAY 0.723404 (-925 600);
DISPLAY INVISIBLE (-925 600);
FORCEPROP 0 LAST CDS_LOCATION C1574
J 0
(-675 675);
DISPLAY 1.021277 (-675 675);
DISPLAY INVISIBLE (-675 675);
FORCEPROP 2 LAST $SEC 1
J 2
(-750 675);
DISPLAY 0.680851 (-750 675);
PAINT MONO (-750 675);
DISPLAY INVISIBLE (-750 675);
FORCEPROP 2 LAST CDS_SEC 1
J 2
(-750 675);
DISPLAY 0.680851 (-750 675);
DISPLAY INVISIBLE (-750 675);
FORCEADD Q_CAP_DIFFBUS..2
R 2
(-925 750);
FORCEPROP 1 LAST PART_NUMBER SP_CH4221MEE01
J 2
(-1041 838);
DISPLAY 0.574468 (-1041 838);
PAINT GREEN (-1041 838);
DISPLAY INVISIBLE (-1041 838);
FORCEPROP 2 LAST VALUE DIFF BUS_0.22UF
J 2
(-1075 750);
DISPLAY 0.553191 (-1075 750);
FORCEPROP 1 LAST $LOCATION C1573
J 2
(-675 775);
DISPLAY 0.723404 (-675 775);
PAINT GREEN (-675 775);
FORCEPROP 2 LASTPIN (-850 750) $PN 1
J 0
(-840 760);
DISPLAY 0.808511 (-840 760);
FORCEPROP 2 LASTPIN (-1000 750) $PN 2
J 2
(-1010 760);
DISPLAY 0.808511 (-1010 760);
FORCEPROP 1 LAST PIN_NAMES_ROTATE TRUE
J 2
(-925 750);
DISPLAY 0.489362 (-925 750);
PAINT GREEN (-925 750);
DISPLAY INVISIBLE (-925 750);
FORCEPROP 1 LAST CDS_LMAN_SYM_OUTLINE -25,50,25,-50
J 2
(-925 750);
DISPLAY 0.468085 (-925 750);
PAINT GREEN (-925 750);
DISPLAY INVISIBLE (-925 750);
FORCEPROP 2 LAST CDS_LIB pure_quanta
J 2
(-925 750);
DISPLAY INVISIBLE (-925 750);
FORCEPROP 2 LAST VOLTAGE 6.3V
J 2
(-1275 800);
DISPLAY 0.553191 (-1275 800);
DISPLAY INVISIBLE (-1275 800);
FORCEPROP 1 LAST MATERIAL X6S
J 2
(-916 829);
DISPLAY 0.574468 (-916 829);
PAINT GREEN (-916 829);
DISPLAY INVISIBLE (-916 829);
FORCEPROP 2 LAST PACK_TYPE C0201
J 2
(-1100 800);
DISPLAY 0.553191 (-1100 800);
DISPLAY INVISIBLE (-1100 800);
FORCEPROP 2 LAST TOLERANCE 20%
J 2
(-1000 800);
DISPLAY 0.553191 (-1000 800);
DISPLAY INVISIBLE (-1000 800);
FORCEPROP 1 LAST PATH I233
J 2
(-925 750);
DISPLAY 0.723404 (-925 750);
DISPLAY INVISIBLE (-925 750);
FORCEPROP 0 LAST CDS_LOCATION C1573
J 0
(-675 825);
DISPLAY 1.021277 (-675 825);
DISPLAY INVISIBLE (-675 825);
FORCEPROP 2 LAST $SEC 1
J 2
(-750 825);
DISPLAY 0.680851 (-750 825);
PAINT MONO (-750 825);
DISPLAY INVISIBLE (-750 825);
FORCEPROP 2 LAST CDS_SEC 1
J 2
(-750 825);
DISPLAY 0.680851 (-750 825);
DISPLAY INVISIBLE (-750 825);
FORCEADD Q_CAP_DIFFBUS..2
R 2
(-925 800);
FORCEPROP 1 LAST PART_NUMBER SP_CH4221MEE01
J 2
(-1041 888);
DISPLAY 0.574468 (-1041 888);
PAINT GREEN (-1041 888);
DISPLAY INVISIBLE (-1041 888);
FORCEPROP 2 LAST VALUE DIFF BUS_0.22UF
J 2
(-1075 800);
DISPLAY 0.553191 (-1075 800);
FORCEPROP 1 LAST $LOCATION C1572
J 2
(-675 825);
DISPLAY 0.723404 (-675 825);
PAINT GREEN (-675 825);
FORCEPROP 2 LASTPIN (-850 800) $PN 1
J 0
(-840 810);
DISPLAY 0.808511 (-840 810);
FORCEPROP 2 LASTPIN (-1000 800) $PN 2
J 2
(-1010 810);
DISPLAY 0.808511 (-1010 810);
FORCEPROP 1 LAST PIN_NAMES_ROTATE TRUE
J 2
(-925 800);
DISPLAY 0.489362 (-925 800);
PAINT GREEN (-925 800);
DISPLAY INVISIBLE (-925 800);
FORCEPROP 1 LAST CDS_LMAN_SYM_OUTLINE -25,50,25,-50
J 2
(-925 800);
DISPLAY 0.468085 (-925 800);
PAINT GREEN (-925 800);
DISPLAY INVISIBLE (-925 800);
FORCEPROP 2 LAST CDS_LIB pure_quanta
J 2
(-925 800);
DISPLAY INVISIBLE (-925 800);
FORCEPROP 2 LAST VOLTAGE 6.3V
J 2
(-1275 850);
DISPLAY 0.553191 (-1275 850);
DISPLAY INVISIBLE (-1275 850);
FORCEPROP 1 LAST MATERIAL X6S
J 2
(-916 879);
DISPLAY 0.574468 (-916 879);
PAINT GREEN (-916 879);
DISPLAY INVISIBLE (-916 879);
FORCEPROP 2 LAST PACK_TYPE C0201
J 2
(-1100 850);
DISPLAY 0.553191 (-1100 850);
DISPLAY INVISIBLE (-1100 850);
FORCEPROP 2 LAST TOLERANCE 20%
J 2
(-1000 850);
DISPLAY 0.553191 (-1000 850);
DISPLAY INVISIBLE (-1000 850);
FORCEPROP 1 LAST PATH I234
J 2
(-925 800);
DISPLAY 0.723404 (-925 800);
DISPLAY INVISIBLE (-925 800);
FORCEPROP 0 LAST CDS_LOCATION C1572
J 0
(-675 875);
DISPLAY 1.021277 (-675 875);
DISPLAY INVISIBLE (-675 875);
FORCEPROP 2 LAST $SEC 1
J 2
(-750 875);
DISPLAY 0.680851 (-750 875);
PAINT MONO (-750 875);
DISPLAY INVISIBLE (-750 875);
FORCEPROP 2 LAST CDS_SEC 1
J 2
(-750 875);
DISPLAY 0.680851 (-750 875);
DISPLAY INVISIBLE (-750 875);
FORCEADD Q_CAP_DIFFBUS..2
R 2
(-925 1000);
FORCEPROP 1 LAST PART_NUMBER SP_CH4221MEE01
J 2
(-1041 1088);
DISPLAY 0.574468 (-1041 1088);
PAINT GREEN (-1041 1088);
DISPLAY INVISIBLE (-1041 1088);
FORCEPROP 2 LAST VALUE DIFF BUS_0.22UF
J 2
(-1075 1000);
DISPLAY 0.553191 (-1075 1000);
FORCEPROP 1 LAST $LOCATION C1570
J 2
(-675 1025);
DISPLAY 0.723404 (-675 1025);
PAINT GREEN (-675 1025);
FORCEPROP 2 LASTPIN (-850 1000) $PN 1
J 0
(-840 1010);
DISPLAY 0.808511 (-840 1010);
FORCEPROP 2 LASTPIN (-1000 1000) $PN 2
J 2
(-1010 1010);
DISPLAY 0.808511 (-1010 1010);
FORCEPROP 1 LAST PIN_NAMES_ROTATE TRUE
J 2
(-925 1000);
DISPLAY 0.489362 (-925 1000);
PAINT GREEN (-925 1000);
DISPLAY INVISIBLE (-925 1000);
FORCEPROP 2 LAST CDS_LIB pure_quanta
J 2
(-925 1000);
DISPLAY INVISIBLE (-925 1000);
FORCEPROP 1 LAST CDS_LMAN_SYM_OUTLINE -25,50,25,-50
J 2
(-925 1000);
DISPLAY 0.468085 (-925 1000);
PAINT GREEN (-925 1000);
DISPLAY INVISIBLE (-925 1000);
FORCEPROP 2 LAST VOLTAGE 6.3V
J 2
(-1275 1050);
DISPLAY 0.553191 (-1275 1050);
DISPLAY INVISIBLE (-1275 1050);
FORCEPROP 1 LAST MATERIAL X6S
J 2
(-916 1079);
DISPLAY 0.574468 (-916 1079);
PAINT GREEN (-916 1079);
DISPLAY INVISIBLE (-916 1079);
FORCEPROP 2 LAST PACK_TYPE C0201
J 2
(-1100 1050);
DISPLAY 0.553191 (-1100 1050);
DISPLAY INVISIBLE (-1100 1050);
FORCEPROP 2 LAST TOLERANCE 20%
J 2
(-1000 1050);
DISPLAY 0.553191 (-1000 1050);
DISPLAY INVISIBLE (-1000 1050);
FORCEPROP 1 LAST PATH I235
J 2
(-925 1000);
DISPLAY 0.723404 (-925 1000);
DISPLAY INVISIBLE (-925 1000);
FORCEPROP 0 LAST CDS_LOCATION C1570
J 0
(-675 1075);
DISPLAY 1.021277 (-675 1075);
DISPLAY INVISIBLE (-675 1075);
FORCEPROP 2 LAST $SEC 1
J 2
(-750 1075);
DISPLAY 0.680851 (-750 1075);
PAINT MONO (-750 1075);
DISPLAY INVISIBLE (-750 1075);
FORCEPROP 2 LAST CDS_SEC 1
J 2
(-750 1075);
DISPLAY 0.680851 (-750 1075);
DISPLAY INVISIBLE (-750 1075);
FORCEADD Q_CAP_DIFFBUS..2
R 2
(-925 950);
FORCEPROP 1 LAST PART_NUMBER SP_CH4221MEE01
J 2
(-1041 1038);
DISPLAY 0.574468 (-1041 1038);
PAINT GREEN (-1041 1038);
DISPLAY INVISIBLE (-1041 1038);
FORCEPROP 2 LAST VALUE DIFF BUS_0.22UF
J 2
(-1075 950);
DISPLAY 0.553191 (-1075 950);
FORCEPROP 1 LAST $LOCATION C1571
J 2
(-675 975);
DISPLAY 0.723404 (-675 975);
PAINT GREEN (-675 975);
FORCEPROP 2 LASTPIN (-850 950) $PN 1
J 0
(-840 960);
DISPLAY 0.808511 (-840 960);
FORCEPROP 2 LASTPIN (-1000 950) $PN 2
J 2
(-1010 960);
DISPLAY 0.808511 (-1010 960);
FORCEPROP 1 LAST PIN_NAMES_ROTATE TRUE
J 2
(-925 950);
DISPLAY 0.489362 (-925 950);
PAINT GREEN (-925 950);
DISPLAY INVISIBLE (-925 950);
FORCEPROP 2 LAST CDS_LIB pure_quanta
J 2
(-925 950);
DISPLAY INVISIBLE (-925 950);
FORCEPROP 1 LAST CDS_LMAN_SYM_OUTLINE -25,50,25,-50
J 2
(-925 950);
DISPLAY 0.468085 (-925 950);
PAINT GREEN (-925 950);
DISPLAY INVISIBLE (-925 950);
FORCEPROP 2 LAST VOLTAGE 6.3V
J 2
(-1275 1000);
DISPLAY 0.553191 (-1275 1000);
DISPLAY INVISIBLE (-1275 1000);
FORCEPROP 1 LAST MATERIAL X6S
J 2
(-916 1029);
DISPLAY 0.574468 (-916 1029);
PAINT GREEN (-916 1029);
DISPLAY INVISIBLE (-916 1029);
FORCEPROP 2 LAST PACK_TYPE C0201
J 2
(-1100 1000);
DISPLAY 0.553191 (-1100 1000);
DISPLAY INVISIBLE (-1100 1000);
FORCEPROP 2 LAST TOLERANCE 20%
J 2
(-1000 1000);
DISPLAY 0.553191 (-1000 1000);
DISPLAY INVISIBLE (-1000 1000);
FORCEPROP 1 LAST PATH I236
J 2
(-925 950);
DISPLAY 0.723404 (-925 950);
DISPLAY INVISIBLE (-925 950);
FORCEPROP 0 LAST CDS_LOCATION C1571
J 0
(-675 1025);
DISPLAY 1.021277 (-675 1025);
DISPLAY INVISIBLE (-675 1025);
FORCEPROP 2 LAST $SEC 1
J 2
(-750 1025);
DISPLAY 0.680851 (-750 1025);
PAINT MONO (-750 1025);
DISPLAY INVISIBLE (-750 1025);
FORCEPROP 2 LAST CDS_SEC 1
J 2
(-750 1025);
DISPLAY 0.680851 (-750 1025);
DISPLAY INVISIBLE (-750 1025);
FORCEADD Q_CAP_DIFFBUS..2
R 2
(-925 1150);
FORCEPROP 1 LAST PART_NUMBER SP_CH4221MEE01
J 2
(-1041 1238);
DISPLAY 0.574468 (-1041 1238);
PAINT GREEN (-1041 1238);
DISPLAY INVISIBLE (-1041 1238);
FORCEPROP 2 LAST VALUE DIFF BUS_0.22UF
J 2
(-1075 1150);
DISPLAY 0.553191 (-1075 1150);
FORCEPROP 1 LAST $LOCATION C1569
J 2
(-675 1175);
DISPLAY 0.723404 (-675 1175);
PAINT GREEN (-675 1175);
FORCEPROP 2 LASTPIN (-850 1150) $PN 1
J 0
(-840 1160);
DISPLAY 0.808511 (-840 1160);
FORCEPROP 2 LASTPIN (-1000 1150) $PN 2
J 2
(-1010 1160);
DISPLAY 0.808511 (-1010 1160);
FORCEPROP 1 LAST PIN_NAMES_ROTATE TRUE
J 2
(-925 1150);
DISPLAY 0.489362 (-925 1150);
PAINT GREEN (-925 1150);
DISPLAY INVISIBLE (-925 1150);
FORCEPROP 2 LAST CDS_LIB pure_quanta
J 2
(-925 1150);
DISPLAY INVISIBLE (-925 1150);
FORCEPROP 1 LAST CDS_LMAN_SYM_OUTLINE -25,50,25,-50
J 2
(-925 1150);
DISPLAY 0.468085 (-925 1150);
PAINT GREEN (-925 1150);
DISPLAY INVISIBLE (-925 1150);
FORCEPROP 2 LAST VOLTAGE 6.3V
J 2
(-1275 1200);
DISPLAY 0.553191 (-1275 1200);
DISPLAY INVISIBLE (-1275 1200);
FORCEPROP 1 LAST MATERIAL X6S
J 2
(-916 1229);
DISPLAY 0.574468 (-916 1229);
PAINT GREEN (-916 1229);
DISPLAY INVISIBLE (-916 1229);
FORCEPROP 2 LAST PACK_TYPE C0201
J 2
(-1100 1200);
DISPLAY 0.553191 (-1100 1200);
DISPLAY INVISIBLE (-1100 1200);
FORCEPROP 2 LAST TOLERANCE 20%
J 2
(-1000 1200);
DISPLAY 0.553191 (-1000 1200);
DISPLAY INVISIBLE (-1000 1200);
FORCEPROP 1 LAST PATH I237
J 2
(-925 1150);
DISPLAY 0.723404 (-925 1150);
DISPLAY INVISIBLE (-925 1150);
FORCEPROP 0 LAST CDS_LOCATION C1569
J 0
(-675 1225);
DISPLAY 1.021277 (-675 1225);
DISPLAY INVISIBLE (-675 1225);
FORCEPROP 2 LAST $SEC 1
J 2
(-750 1225);
DISPLAY 0.680851 (-750 1225);
PAINT MONO (-750 1225);
DISPLAY INVISIBLE (-750 1225);
FORCEPROP 2 LAST CDS_SEC 1
J 2
(-750 1225);
DISPLAY 0.680851 (-750 1225);
DISPLAY INVISIBLE (-750 1225);
FORCEADD Q_CAP_DIFFBUS..2
R 2
(-925 1200);
FORCEPROP 1 LAST PART_NUMBER SP_CH4221MEE01
J 2
(-1041 1288);
DISPLAY 0.574468 (-1041 1288);
PAINT GREEN (-1041 1288);
DISPLAY INVISIBLE (-1041 1288);
FORCEPROP 2 LAST VALUE DIFF BUS_0.22UF
J 2
(-1075 1200);
DISPLAY 0.553191 (-1075 1200);
FORCEPROP 1 LAST $LOCATION C1568
J 2
(-675 1225);
DISPLAY 0.723404 (-675 1225);
PAINT GREEN (-675 1225);
FORCEPROP 2 LASTPIN (-850 1200) $PN 1
J 0
(-840 1210);
DISPLAY 0.808511 (-840 1210);
FORCEPROP 2 LASTPIN (-1000 1200) $PN 2
J 2
(-1010 1210);
DISPLAY 0.808511 (-1010 1210);
FORCEPROP 1 LAST PIN_NAMES_ROTATE TRUE
J 2
(-925 1200);
DISPLAY 0.489362 (-925 1200);
PAINT GREEN (-925 1200);
DISPLAY INVISIBLE (-925 1200);
FORCEPROP 2 LAST CDS_LIB pure_quanta
J 2
(-925 1200);
DISPLAY INVISIBLE (-925 1200);
FORCEPROP 1 LAST CDS_LMAN_SYM_OUTLINE -25,50,25,-50
J 2
(-925 1200);
DISPLAY 0.468085 (-925 1200);
PAINT GREEN (-925 1200);
DISPLAY INVISIBLE (-925 1200);
FORCEPROP 2 LAST VOLTAGE 6.3V
J 2
(-1275 1250);
DISPLAY 0.553191 (-1275 1250);
DISPLAY INVISIBLE (-1275 1250);
FORCEPROP 1 LAST MATERIAL X6S
J 2
(-916 1279);
DISPLAY 0.574468 (-916 1279);
PAINT GREEN (-916 1279);
DISPLAY INVISIBLE (-916 1279);
FORCEPROP 2 LAST PACK_TYPE C0201
J 2
(-1100 1250);
DISPLAY 0.553191 (-1100 1250);
DISPLAY INVISIBLE (-1100 1250);
FORCEPROP 2 LAST TOLERANCE 20%
J 2
(-1000 1250);
DISPLAY 0.553191 (-1000 1250);
DISPLAY INVISIBLE (-1000 1250);
FORCEPROP 1 LAST PATH I238
J 2
(-925 1200);
DISPLAY 0.723404 (-925 1200);
DISPLAY INVISIBLE (-925 1200);
FORCEPROP 0 LAST CDS_LOCATION C1568
J 0
(-675 1275);
DISPLAY 1.021277 (-675 1275);
DISPLAY INVISIBLE (-675 1275);
FORCEPROP 2 LAST $SEC 1
J 2
(-750 1275);
DISPLAY 0.680851 (-750 1275);
PAINT MONO (-750 1275);
DISPLAY INVISIBLE (-750 1275);
FORCEPROP 2 LAST CDS_SEC 1
J 2
(-750 1275);
DISPLAY 0.680851 (-750 1275);
DISPLAY INVISIBLE (-750 1275);
FORCEADD Q_CAP_DIFFBUS..2
R 2
(-925 1350);
FORCEPROP 1 LAST PART_NUMBER SP_CH4221MEE01
J 2
(-1041 1438);
DISPLAY 0.574468 (-1041 1438);
PAINT GREEN (-1041 1438);
DISPLAY INVISIBLE (-1041 1438);
FORCEPROP 2 LAST VALUE DIFF BUS_0.22UF
J 2
(-1075 1350);
DISPLAY 0.553191 (-1075 1350);
FORCEPROP 1 LAST $LOCATION C1567
J 2
(-675 1375);
DISPLAY 0.723404 (-675 1375);
PAINT GREEN (-675 1375);
FORCEPROP 2 LASTPIN (-850 1350) $PN 1
J 0
(-840 1360);
DISPLAY 0.808511 (-840 1360);
FORCEPROP 2 LASTPIN (-1000 1350) $PN 2
J 2
(-1010 1360);
DISPLAY 0.808511 (-1010 1360);
FORCEPROP 1 LAST PIN_NAMES_ROTATE TRUE
J 2
(-925 1350);
DISPLAY 0.489362 (-925 1350);
PAINT GREEN (-925 1350);
DISPLAY INVISIBLE (-925 1350);
FORCEPROP 2 LAST CDS_LIB pure_quanta
J 2
(-925 1350);
DISPLAY INVISIBLE (-925 1350);
FORCEPROP 1 LAST CDS_LMAN_SYM_OUTLINE -25,50,25,-50
J 2
(-925 1350);
DISPLAY 0.468085 (-925 1350);
PAINT GREEN (-925 1350);
DISPLAY INVISIBLE (-925 1350);
FORCEPROP 2 LAST VOLTAGE 6.3V
J 2
(-1275 1400);
DISPLAY 0.553191 (-1275 1400);
DISPLAY INVISIBLE (-1275 1400);
FORCEPROP 1 LAST MATERIAL X6S
J 2
(-916 1429);
DISPLAY 0.574468 (-916 1429);
PAINT GREEN (-916 1429);
DISPLAY INVISIBLE (-916 1429);
FORCEPROP 2 LAST PACK_TYPE C0201
J 2
(-1100 1400);
DISPLAY 0.553191 (-1100 1400);
DISPLAY INVISIBLE (-1100 1400);
FORCEPROP 2 LAST TOLERANCE 20%
J 2
(-1000 1400);
DISPLAY 0.553191 (-1000 1400);
DISPLAY INVISIBLE (-1000 1400);
FORCEPROP 1 LAST PATH I239
J 2
(-925 1350);
DISPLAY 0.723404 (-925 1350);
DISPLAY INVISIBLE (-925 1350);
FORCEPROP 0 LAST CDS_LOCATION C1567
J 0
(-675 1425);
DISPLAY 1.021277 (-675 1425);
DISPLAY INVISIBLE (-675 1425);
FORCEPROP 2 LAST $SEC 1
J 2
(-750 1425);
DISPLAY 0.680851 (-750 1425);
PAINT MONO (-750 1425);
DISPLAY INVISIBLE (-750 1425);
FORCEPROP 2 LAST CDS_SEC 1
J 2
(-750 1425);
DISPLAY 0.680851 (-750 1425);
DISPLAY INVISIBLE (-750 1425);
FORCEADD Q_CAP_DIFFBUS..2
R 2
(-925 1400);
FORCEPROP 1 LAST PART_NUMBER SP_CH4221MEE01
J 2
(-1041 1488);
DISPLAY 0.574468 (-1041 1488);
PAINT GREEN (-1041 1488);
DISPLAY INVISIBLE (-1041 1488);
FORCEPROP 2 LAST VALUE DIFF BUS_0.22UF
J 2
(-1075 1400);
DISPLAY 0.553191 (-1075 1400);
FORCEPROP 1 LAST $LOCATION C1566
J 2
(-675 1425);
DISPLAY 0.723404 (-675 1425);
PAINT GREEN (-675 1425);
FORCEPROP 2 LASTPIN (-850 1400) $PN 1
J 0
(-840 1410);
DISPLAY 0.808511 (-840 1410);
FORCEPROP 2 LASTPIN (-1000 1400) $PN 2
J 2
(-1010 1410);
DISPLAY 0.808511 (-1010 1410);
FORCEPROP 1 LAST PIN_NAMES_ROTATE TRUE
J 2
(-925 1400);
DISPLAY 0.489362 (-925 1400);
PAINT GREEN (-925 1400);
DISPLAY INVISIBLE (-925 1400);
FORCEPROP 2 LAST CDS_LIB pure_quanta
J 2
(-925 1400);
DISPLAY INVISIBLE (-925 1400);
FORCEPROP 1 LAST CDS_LMAN_SYM_OUTLINE -25,50,25,-50
J 2
(-925 1400);
DISPLAY 0.468085 (-925 1400);
PAINT GREEN (-925 1400);
DISPLAY INVISIBLE (-925 1400);
FORCEPROP 2 LAST VOLTAGE 6.3V
J 2
(-1275 1450);
DISPLAY 0.553191 (-1275 1450);
DISPLAY INVISIBLE (-1275 1450);
FORCEPROP 1 LAST MATERIAL X6S
J 2
(-916 1479);
DISPLAY 0.574468 (-916 1479);
PAINT GREEN (-916 1479);
DISPLAY INVISIBLE (-916 1479);
FORCEPROP 2 LAST PACK_TYPE C0201
J 2
(-1100 1450);
DISPLAY 0.553191 (-1100 1450);
DISPLAY INVISIBLE (-1100 1450);
FORCEPROP 2 LAST TOLERANCE 20%
J 2
(-1000 1450);
DISPLAY 0.553191 (-1000 1450);
DISPLAY INVISIBLE (-1000 1450);
FORCEPROP 1 LAST PATH I240
J 2
(-925 1400);
DISPLAY 0.723404 (-925 1400);
DISPLAY INVISIBLE (-925 1400);
FORCEPROP 0 LAST CDS_LOCATION C1566
J 0
(-675 1475);
DISPLAY 1.021277 (-675 1475);
DISPLAY INVISIBLE (-675 1475);
FORCEPROP 2 LAST $SEC 1
J 2
(-750 1475);
DISPLAY 0.680851 (-750 1475);
PAINT MONO (-750 1475);
DISPLAY INVISIBLE (-750 1475);
FORCEPROP 2 LAST CDS_SEC 1
J 2
(-750 1475);
DISPLAY 0.680851 (-750 1475);
DISPLAY INVISIBLE (-750 1475);
FORCEADD Q_CAP_DIFFBUS..2
R 2
(-925 1550);
FORCEPROP 1 LAST PART_NUMBER SP_CH4221MEE01
J 2
(-1041 1638);
DISPLAY 0.574468 (-1041 1638);
PAINT GREEN (-1041 1638);
DISPLAY INVISIBLE (-1041 1638);
FORCEPROP 2 LAST VALUE DIFF BUS_0.22UF
J 2
(-1075 1550);
DISPLAY 0.553191 (-1075 1550);
FORCEPROP 1 LAST $LOCATION C1565
J 2
(-675 1575);
DISPLAY 0.723404 (-675 1575);
PAINT GREEN (-675 1575);
FORCEPROP 2 LASTPIN (-850 1550) $PN 1
J 0
(-840 1560);
DISPLAY 0.808511 (-840 1560);
FORCEPROP 2 LASTPIN (-1000 1550) $PN 2
J 2
(-1010 1560);
DISPLAY 0.808511 (-1010 1560);
FORCEPROP 1 LAST PIN_NAMES_ROTATE TRUE
J 2
(-925 1550);
DISPLAY 0.489362 (-925 1550);
PAINT GREEN (-925 1550);
DISPLAY INVISIBLE (-925 1550);
FORCEPROP 2 LAST CDS_LIB pure_quanta
J 2
(-925 1550);
DISPLAY INVISIBLE (-925 1550);
FORCEPROP 1 LAST CDS_LMAN_SYM_OUTLINE -25,50,25,-50
J 2
(-925 1550);
DISPLAY 0.468085 (-925 1550);
PAINT GREEN (-925 1550);
DISPLAY INVISIBLE (-925 1550);
FORCEPROP 2 LAST VOLTAGE 6.3V
J 2
(-1275 1600);
DISPLAY 0.553191 (-1275 1600);
DISPLAY INVISIBLE (-1275 1600);
FORCEPROP 1 LAST MATERIAL X6S
J 2
(-916 1629);
DISPLAY 0.574468 (-916 1629);
PAINT GREEN (-916 1629);
DISPLAY INVISIBLE (-916 1629);
FORCEPROP 2 LAST PACK_TYPE C0201
J 2
(-1100 1600);
DISPLAY 0.553191 (-1100 1600);
DISPLAY INVISIBLE (-1100 1600);
FORCEPROP 2 LAST TOLERANCE 20%
J 2
(-1000 1600);
DISPLAY 0.553191 (-1000 1600);
DISPLAY INVISIBLE (-1000 1600);
FORCEPROP 1 LAST PATH I241
J 2
(-925 1550);
DISPLAY 0.723404 (-925 1550);
DISPLAY INVISIBLE (-925 1550);
FORCEPROP 0 LAST CDS_LOCATION C1565
J 0
(-675 1625);
DISPLAY 1.021277 (-675 1625);
DISPLAY INVISIBLE (-675 1625);
FORCEPROP 2 LAST $SEC 1
J 2
(-750 1625);
DISPLAY 0.680851 (-750 1625);
PAINT MONO (-750 1625);
DISPLAY INVISIBLE (-750 1625);
FORCEPROP 2 LAST CDS_SEC 1
J 2
(-750 1625);
DISPLAY 0.680851 (-750 1625);
DISPLAY INVISIBLE (-750 1625);
FORCEADD Q_CAP_DIFFBUS..2
R 2
(-925 1600);
FORCEPROP 1 LAST PART_NUMBER SP_CH4221MEE01
J 2
(-1041 1688);
DISPLAY 0.574468 (-1041 1688);
PAINT GREEN (-1041 1688);
DISPLAY INVISIBLE (-1041 1688);
FORCEPROP 2 LAST VALUE DIFF BUS_0.22UF
J 2
(-1075 1600);
DISPLAY 0.553191 (-1075 1600);
FORCEPROP 1 LAST $LOCATION C1564
J 2
(-675 1625);
DISPLAY 0.723404 (-675 1625);
PAINT GREEN (-675 1625);
FORCEPROP 2 LASTPIN (-850 1600) $PN 1
J 0
(-840 1610);
DISPLAY 0.808511 (-840 1610);
FORCEPROP 2 LASTPIN (-1000 1600) $PN 2
J 2
(-1010 1610);
DISPLAY 0.808511 (-1010 1610);
FORCEPROP 1 LAST PIN_NAMES_ROTATE TRUE
J 2
(-925 1600);
DISPLAY 0.489362 (-925 1600);
PAINT GREEN (-925 1600);
DISPLAY INVISIBLE (-925 1600);
FORCEPROP 1 LAST CDS_LMAN_SYM_OUTLINE -25,50,25,-50
J 2
(-925 1600);
DISPLAY 0.468085 (-925 1600);
PAINT GREEN (-925 1600);
DISPLAY INVISIBLE (-925 1600);
FORCEPROP 2 LAST CDS_LIB pure_quanta
J 2
(-925 1600);
DISPLAY INVISIBLE (-925 1600);
FORCEPROP 2 LAST VOLTAGE 6.3V
J 2
(-1275 1650);
DISPLAY 0.553191 (-1275 1650);
DISPLAY INVISIBLE (-1275 1650);
FORCEPROP 1 LAST MATERIAL X6S
J 2
(-916 1679);
DISPLAY 0.574468 (-916 1679);
PAINT GREEN (-916 1679);
DISPLAY INVISIBLE (-916 1679);
FORCEPROP 2 LAST PACK_TYPE C0201
J 2
(-1100 1650);
DISPLAY 0.553191 (-1100 1650);
DISPLAY INVISIBLE (-1100 1650);
FORCEPROP 2 LAST TOLERANCE 20%
J 2
(-1000 1650);
DISPLAY 0.553191 (-1000 1650);
DISPLAY INVISIBLE (-1000 1650);
FORCEPROP 1 LAST PATH I242
J 2
(-925 1600);
DISPLAY 0.723404 (-925 1600);
DISPLAY INVISIBLE (-925 1600);
FORCEPROP 0 LAST CDS_LOCATION C1564
J 0
(-675 1675);
DISPLAY 1.021277 (-675 1675);
DISPLAY INVISIBLE (-675 1675);
FORCEPROP 2 LAST $SEC 1
J 2
(-750 1675);
DISPLAY 0.680851 (-750 1675);
PAINT MONO (-750 1675);
DISPLAY INVISIBLE (-750 1675);
FORCEPROP 2 LAST CDS_SEC 1
J 2
(-750 1675);
DISPLAY 0.680851 (-750 1675);
DISPLAY INVISIBLE (-750 1675);
FORCEADD TAP..1
R 2
(-1900 2125);
FORCEPROP 3 LASTPIN (-1850 2125) SIG_NAME P5E_CPU0_PE4_TX_DP<8>
J 0
(-1840 2135);
DISPLAY 0.659574 (-1840 2135);
PAINT MONO (-1840 2135);
DISPLAY INVISIBLE (-1840 2135);
FORCEPROP 1 LASTPIN (-1850 2125) BN 8
J 2
(-1838 2133);
DISPLAY 0.680851 (-1838 2133);
PAINT GREEN (-1838 2133);
FORCEPROP 2 LAST CDS_LIB standard
J 0
(-1900 2125);
DISPLAY INVISIBLE (-1900 2125);
FORCEPROP 1 LAST BODY_TYPE PLUMBING
J 2
(-1900 2175);
DISPLAY 0.872340 (-1900 2175);
PAINT GREEN (-1900 2175);
DISPLAY INVISIBLE (-1900 2175);
FORCEPROP 1 LAST HDL_TAP TRUE
J 2
(-2225 2000);
DISPLAY 0.872340 (-2225 2000);
DISPLAY INVISIBLE (-2225 2000);
FORCEPROP 1 LAST PATH I243
J 2
(-1898 2125);
DISPLAY 0.872340 (-1898 2125);
PAINT GREEN (-1898 2125);
DISPLAY INVISIBLE (-1898 2125);
FORCEADD TAP..1
R 2
(-1900 2325);
FORCEPROP 3 LASTPIN (-1850 2325) SIG_NAME P5E_CPU0_PE4_TX_DP<9>
J 0
(-1840 2335);
DISPLAY 0.659574 (-1840 2335);
PAINT MONO (-1840 2335);
DISPLAY INVISIBLE (-1840 2335);
FORCEPROP 1 LASTPIN (-1850 2325) BN 9
J 2
(-1838 2333);
DISPLAY 0.680851 (-1838 2333);
PAINT GREEN (-1838 2333);
FORCEPROP 2 LAST CDS_LIB standard
J 0
(-1900 2325);
DISPLAY INVISIBLE (-1900 2325);
FORCEPROP 1 LAST BODY_TYPE PLUMBING
J 2
(-1900 2375);
DISPLAY 0.872340 (-1900 2375);
PAINT GREEN (-1900 2375);
DISPLAY INVISIBLE (-1900 2375);
FORCEPROP 1 LAST HDL_TAP TRUE
J 2
(-2225 2200);
DISPLAY 0.872340 (-2225 2200);
DISPLAY INVISIBLE (-2225 2200);
FORCEPROP 1 LAST PATH I244
J 2
(-1898 2325);
DISPLAY 0.872340 (-1898 2325);
PAINT GREEN (-1898 2325);
DISPLAY INVISIBLE (-1898 2325);
FORCEADD TAP..1
R 2
(-1900 2525);
FORCEPROP 3 LASTPIN (-1850 2525) SIG_NAME P5E_CPU0_PE4_TX_DP<10>
J 0
(-1840 2535);
DISPLAY 0.659574 (-1840 2535);
PAINT MONO (-1840 2535);
DISPLAY INVISIBLE (-1840 2535);
FORCEPROP 1 LASTPIN (-1850 2525) BN 10
J 2
(-1838 2533);
DISPLAY 0.680851 (-1838 2533);
PAINT GREEN (-1838 2533);
FORCEPROP 2 LAST CDS_LIB standard
J 0
(-1900 2525);
DISPLAY INVISIBLE (-1900 2525);
FORCEPROP 1 LAST BODY_TYPE PLUMBING
J 2
(-1900 2575);
DISPLAY 0.872340 (-1900 2575);
PAINT GREEN (-1900 2575);
DISPLAY INVISIBLE (-1900 2575);
FORCEPROP 1 LAST HDL_TAP TRUE
J 2
(-2225 2400);
DISPLAY 0.872340 (-2225 2400);
DISPLAY INVISIBLE (-2225 2400);
FORCEPROP 1 LAST PATH I245
J 2
(-1898 2525);
DISPLAY 0.872340 (-1898 2525);
PAINT GREEN (-1898 2525);
DISPLAY INVISIBLE (-1898 2525);
FORCEADD TAP..1
R 2
(-1650 2175);
FORCEPROP 3 LASTPIN (-1600 2175) SIG_NAME P5E_CPU0_PE4_TX_DN<8>
J 0
(-1590 2185);
DISPLAY 0.659574 (-1590 2185);
PAINT MONO (-1590 2185);
DISPLAY INVISIBLE (-1590 2185);
FORCEPROP 1 LASTPIN (-1600 2175) BN 8
J 2
(-1588 2183);
DISPLAY 0.680851 (-1588 2183);
PAINT GREEN (-1588 2183);
FORCEPROP 2 LAST CDS_LIB standard
J 0
(-1650 2175);
DISPLAY INVISIBLE (-1650 2175);
FORCEPROP 1 LAST BODY_TYPE PLUMBING
J 2
(-1650 2225);
DISPLAY 0.872340 (-1650 2225);
PAINT GREEN (-1650 2225);
DISPLAY INVISIBLE (-1650 2225);
FORCEPROP 1 LAST HDL_TAP TRUE
J 2
(-1975 2050);
DISPLAY 0.872340 (-1975 2050);
DISPLAY INVISIBLE (-1975 2050);
FORCEPROP 1 LAST PATH I246
J 2
(-1648 2175);
DISPLAY 0.872340 (-1648 2175);
PAINT GREEN (-1648 2175);
DISPLAY INVISIBLE (-1648 2175);
FORCEADD TAP..1
R 2
(-1650 2375);
FORCEPROP 3 LASTPIN (-1600 2375) SIG_NAME P5E_CPU0_PE4_TX_DN<9>
J 0
(-1590 2385);
DISPLAY 0.659574 (-1590 2385);
PAINT MONO (-1590 2385);
DISPLAY INVISIBLE (-1590 2385);
FORCEPROP 1 LASTPIN (-1600 2375) BN 9
J 2
(-1588 2383);
DISPLAY 0.680851 (-1588 2383);
PAINT GREEN (-1588 2383);
FORCEPROP 2 LAST CDS_LIB standard
J 0
(-1650 2375);
DISPLAY INVISIBLE (-1650 2375);
FORCEPROP 1 LAST BODY_TYPE PLUMBING
J 2
(-1650 2425);
DISPLAY 0.872340 (-1650 2425);
PAINT GREEN (-1650 2425);
DISPLAY INVISIBLE (-1650 2425);
FORCEPROP 1 LAST HDL_TAP TRUE
J 2
(-1975 2250);
DISPLAY 0.872340 (-1975 2250);
DISPLAY INVISIBLE (-1975 2250);
FORCEPROP 1 LAST PATH I247
J 2
(-1648 2375);
DISPLAY 0.872340 (-1648 2375);
PAINT GREEN (-1648 2375);
DISPLAY INVISIBLE (-1648 2375);
FORCEADD TAP..1
R 2
(-1900 2725);
FORCEPROP 3 LASTPIN (-1850 2725) SIG_NAME P5E_CPU0_PE4_TX_DP<11>
J 0
(-1840 2735);
DISPLAY 0.659574 (-1840 2735);
PAINT MONO (-1840 2735);
DISPLAY INVISIBLE (-1840 2735);
FORCEPROP 1 LASTPIN (-1850 2725) BN 11
J 2
(-1838 2733);
DISPLAY 0.680851 (-1838 2733);
PAINT GREEN (-1838 2733);
FORCEPROP 2 LAST CDS_LIB standard
J 0
(-1900 2725);
DISPLAY INVISIBLE (-1900 2725);
FORCEPROP 1 LAST BODY_TYPE PLUMBING
J 2
(-1900 2775);
DISPLAY 0.872340 (-1900 2775);
PAINT GREEN (-1900 2775);
DISPLAY INVISIBLE (-1900 2775);
FORCEPROP 1 LAST HDL_TAP TRUE
J 2
(-2225 2600);
DISPLAY 0.872340 (-2225 2600);
DISPLAY INVISIBLE (-2225 2600);
FORCEPROP 1 LAST PATH I248
J 2
(-1898 2725);
DISPLAY 0.872340 (-1898 2725);
PAINT GREEN (-1898 2725);
DISPLAY INVISIBLE (-1898 2725);
FORCEADD TAP..1
R 2
(-1900 2925);
FORCEPROP 3 LASTPIN (-1850 2925) SIG_NAME P5E_CPU0_PE4_TX_DP<12>
J 0
(-1840 2935);
DISPLAY 0.659574 (-1840 2935);
PAINT MONO (-1840 2935);
DISPLAY INVISIBLE (-1840 2935);
FORCEPROP 1 LASTPIN (-1850 2925) BN 12
J 2
(-1838 2933);
DISPLAY 0.680851 (-1838 2933);
PAINT GREEN (-1838 2933);
FORCEPROP 2 LAST CDS_LIB standard
J 0
(-1900 2925);
DISPLAY INVISIBLE (-1900 2925);
FORCEPROP 1 LAST BODY_TYPE PLUMBING
J 2
(-1900 2975);
DISPLAY 0.872340 (-1900 2975);
PAINT GREEN (-1900 2975);
DISPLAY INVISIBLE (-1900 2975);
FORCEPROP 1 LAST HDL_TAP TRUE
J 2
(-2225 2800);
DISPLAY 0.872340 (-2225 2800);
DISPLAY INVISIBLE (-2225 2800);
FORCEPROP 1 LAST PATH I249
J 2
(-1898 2925);
DISPLAY 0.872340 (-1898 2925);
PAINT GREEN (-1898 2925);
DISPLAY INVISIBLE (-1898 2925);
FORCEADD TAP..1
R 2
(-1650 2775);
FORCEPROP 3 LASTPIN (-1600 2775) SIG_NAME P5E_CPU0_PE4_TX_DN<11>
J 0
(-1590 2785);
DISPLAY 0.659574 (-1590 2785);
PAINT MONO (-1590 2785);
DISPLAY INVISIBLE (-1590 2785);
FORCEPROP 1 LASTPIN (-1600 2775) BN 11
J 2
(-1588 2783);
DISPLAY 0.680851 (-1588 2783);
PAINT GREEN (-1588 2783);
FORCEPROP 2 LAST CDS_LIB standard
J 0
(-1650 2775);
DISPLAY INVISIBLE (-1650 2775);
FORCEPROP 1 LAST BODY_TYPE PLUMBING
J 2
(-1650 2825);
DISPLAY 0.872340 (-1650 2825);
PAINT GREEN (-1650 2825);
DISPLAY INVISIBLE (-1650 2825);
FORCEPROP 1 LAST HDL_TAP TRUE
J 2
(-1975 2650);
DISPLAY 0.872340 (-1975 2650);
DISPLAY INVISIBLE (-1975 2650);
FORCEPROP 1 LAST PATH I250
J 2
(-1648 2775);
DISPLAY 0.872340 (-1648 2775);
PAINT GREEN (-1648 2775);
DISPLAY INVISIBLE (-1648 2775);
FORCEADD TAP..1
R 2
(-1650 2575);
FORCEPROP 3 LASTPIN (-1600 2575) SIG_NAME P5E_CPU0_PE4_TX_DN<10>
J 0
(-1590 2585);
DISPLAY 0.659574 (-1590 2585);
PAINT MONO (-1590 2585);
DISPLAY INVISIBLE (-1590 2585);
FORCEPROP 1 LASTPIN (-1600 2575) BN 10
J 2
(-1588 2583);
DISPLAY 0.680851 (-1588 2583);
PAINT GREEN (-1588 2583);
FORCEPROP 2 LAST CDS_LIB standard
J 0
(-1650 2575);
DISPLAY INVISIBLE (-1650 2575);
FORCEPROP 1 LAST BODY_TYPE PLUMBING
J 2
(-1650 2625);
DISPLAY 0.872340 (-1650 2625);
PAINT GREEN (-1650 2625);
DISPLAY INVISIBLE (-1650 2625);
FORCEPROP 1 LAST HDL_TAP TRUE
J 2
(-1975 2450);
DISPLAY 0.872340 (-1975 2450);
DISPLAY INVISIBLE (-1975 2450);
FORCEPROP 1 LAST PATH I251
J 2
(-1648 2575);
DISPLAY 0.872340 (-1648 2575);
PAINT GREEN (-1648 2575);
DISPLAY INVISIBLE (-1648 2575);
FORCEADD TAP..1
R 2
(-1650 2975);
FORCEPROP 3 LASTPIN (-1600 2975) SIG_NAME P5E_CPU0_PE4_TX_DN<12>
J 0
(-1590 2985);
DISPLAY 0.659574 (-1590 2985);
PAINT MONO (-1590 2985);
DISPLAY INVISIBLE (-1590 2985);
FORCEPROP 1 LASTPIN (-1600 2975) BN 12
J 2
(-1588 2983);
DISPLAY 0.680851 (-1588 2983);
PAINT GREEN (-1588 2983);
FORCEPROP 2 LAST CDS_LIB standard
J 0
(-1650 2975);
DISPLAY INVISIBLE (-1650 2975);
FORCEPROP 1 LAST BODY_TYPE PLUMBING
J 2
(-1650 3025);
DISPLAY 0.872340 (-1650 3025);
PAINT GREEN (-1650 3025);
DISPLAY INVISIBLE (-1650 3025);
FORCEPROP 1 LAST HDL_TAP TRUE
J 2
(-1975 2850);
DISPLAY 0.872340 (-1975 2850);
DISPLAY INVISIBLE (-1975 2850);
FORCEPROP 1 LAST PATH I252
J 2
(-1648 2975);
DISPLAY 0.872340 (-1648 2975);
PAINT GREEN (-1648 2975);
DISPLAY INVISIBLE (-1648 2975);
FORCEADD TAP..1
R 2
(-1900 3325);
FORCEPROP 3 LASTPIN (-1850 3325) SIG_NAME P5E_CPU0_PE4_TX_DP<14>
J 0
(-1840 3335);
DISPLAY 0.659574 (-1840 3335);
PAINT MONO (-1840 3335);
DISPLAY INVISIBLE (-1840 3335);
FORCEPROP 1 LASTPIN (-1850 3325) BN 14
J 2
(-1838 3333);
DISPLAY 0.680851 (-1838 3333);
PAINT GREEN (-1838 3333);
FORCEPROP 2 LAST CDS_LIB standard
J 0
(-1900 3325);
DISPLAY INVISIBLE (-1900 3325);
FORCEPROP 1 LAST BODY_TYPE PLUMBING
J 2
(-1900 3375);
DISPLAY 0.872340 (-1900 3375);
PAINT GREEN (-1900 3375);
DISPLAY INVISIBLE (-1900 3375);
FORCEPROP 1 LAST HDL_TAP TRUE
J 2
(-2225 3200);
DISPLAY 0.872340 (-2225 3200);
DISPLAY INVISIBLE (-2225 3200);
FORCEPROP 1 LAST PATH I253
J 2
(-1898 3325);
DISPLAY 0.872340 (-1898 3325);
PAINT GREEN (-1898 3325);
DISPLAY INVISIBLE (-1898 3325);
FORCEADD TAP..1
R 2
(-1900 3125);
FORCEPROP 3 LASTPIN (-1850 3125) SIG_NAME P5E_CPU0_PE4_TX_DP<13>
J 0
(-1840 3135);
DISPLAY 0.659574 (-1840 3135);
PAINT MONO (-1840 3135);
DISPLAY INVISIBLE (-1840 3135);
FORCEPROP 1 LASTPIN (-1850 3125) BN 13
J 2
(-1838 3133);
DISPLAY 0.680851 (-1838 3133);
PAINT GREEN (-1838 3133);
FORCEPROP 2 LAST CDS_LIB standard
J 0
(-1900 3125);
DISPLAY INVISIBLE (-1900 3125);
FORCEPROP 1 LAST BODY_TYPE PLUMBING
J 2
(-1900 3175);
DISPLAY 0.872340 (-1900 3175);
PAINT GREEN (-1900 3175);
DISPLAY INVISIBLE (-1900 3175);
FORCEPROP 1 LAST HDL_TAP TRUE
J 2
(-2225 3000);
DISPLAY 0.872340 (-2225 3000);
DISPLAY INVISIBLE (-2225 3000);
FORCEPROP 1 LAST PATH I254
J 2
(-1898 3125);
DISPLAY 0.872340 (-1898 3125);
PAINT GREEN (-1898 3125);
DISPLAY INVISIBLE (-1898 3125);
FORCEADD TAP..1
R 2
(-1900 3525);
FORCEPROP 3 LASTPIN (-1850 3525) SIG_NAME P5E_CPU0_PE4_TX_DP<15>
J 0
(-1840 3535);
DISPLAY 0.659574 (-1840 3535);
PAINT MONO (-1840 3535);
DISPLAY INVISIBLE (-1840 3535);
FORCEPROP 1 LASTPIN (-1850 3525) BN 15
J 2
(-1838 3533);
DISPLAY 0.680851 (-1838 3533);
PAINT GREEN (-1838 3533);
FORCEPROP 2 LAST CDS_LIB standard
J 0
(-1900 3525);
DISPLAY INVISIBLE (-1900 3525);
FORCEPROP 1 LAST BODY_TYPE PLUMBING
J 2
(-1900 3575);
DISPLAY 0.872340 (-1900 3575);
PAINT GREEN (-1900 3575);
DISPLAY INVISIBLE (-1900 3575);
FORCEPROP 1 LAST HDL_TAP TRUE
J 2
(-2225 3400);
DISPLAY 0.872340 (-2225 3400);
DISPLAY INVISIBLE (-2225 3400);
FORCEPROP 1 LAST PATH I255
J 2
(-1898 3525);
DISPLAY 0.872340 (-1898 3525);
PAINT GREEN (-1898 3525);
DISPLAY INVISIBLE (-1898 3525);
FORCEADD TAP..1
R 2
(-1650 3175);
FORCEPROP 3 LASTPIN (-1600 3175) SIG_NAME P5E_CPU0_PE4_TX_DN<13>
J 0
(-1590 3185);
DISPLAY 0.659574 (-1590 3185);
PAINT MONO (-1590 3185);
DISPLAY INVISIBLE (-1590 3185);
FORCEPROP 1 LASTPIN (-1600 3175) BN 13
J 2
(-1588 3183);
DISPLAY 0.680851 (-1588 3183);
PAINT GREEN (-1588 3183);
FORCEPROP 2 LAST CDS_LIB standard
J 0
(-1650 3175);
DISPLAY INVISIBLE (-1650 3175);
FORCEPROP 1 LAST BODY_TYPE PLUMBING
J 2
(-1650 3225);
DISPLAY 0.872340 (-1650 3225);
PAINT GREEN (-1650 3225);
DISPLAY INVISIBLE (-1650 3225);
FORCEPROP 1 LAST HDL_TAP TRUE
J 2
(-1975 3050);
DISPLAY 0.872340 (-1975 3050);
DISPLAY INVISIBLE (-1975 3050);
FORCEPROP 1 LAST PATH I256
J 2
(-1648 3175);
DISPLAY 0.872340 (-1648 3175);
PAINT GREEN (-1648 3175);
DISPLAY INVISIBLE (-1648 3175);
FORCEADD TAP..1
R 2
(-1650 3575);
FORCEPROP 3 LASTPIN (-1600 3575) SIG_NAME P5E_CPU0_PE4_TX_DN<15>
J 0
(-1590 3585);
DISPLAY 0.659574 (-1590 3585);
PAINT MONO (-1590 3585);
DISPLAY INVISIBLE (-1590 3585);
FORCEPROP 1 LASTPIN (-1600 3575) BN 15
J 2
(-1588 3583);
DISPLAY 0.680851 (-1588 3583);
PAINT GREEN (-1588 3583);
FORCEPROP 2 LAST CDS_LIB standard
J 0
(-1650 3575);
DISPLAY INVISIBLE (-1650 3575);
FORCEPROP 1 LAST BODY_TYPE PLUMBING
J 2
(-1650 3625);
DISPLAY 0.872340 (-1650 3625);
PAINT GREEN (-1650 3625);
DISPLAY INVISIBLE (-1650 3625);
FORCEPROP 1 LAST HDL_TAP TRUE
J 2
(-1975 3450);
DISPLAY 0.872340 (-1975 3450);
DISPLAY INVISIBLE (-1975 3450);
FORCEPROP 1 LAST PATH I257
J 2
(-1648 3575);
DISPLAY 0.872340 (-1648 3575);
PAINT GREEN (-1648 3575);
DISPLAY INVISIBLE (-1648 3575);
FORCEADD TAP..1
R 2
(-1650 3375);
FORCEPROP 3 LASTPIN (-1600 3375) SIG_NAME P5E_CPU0_PE4_TX_DN<14>
J 0
(-1590 3385);
DISPLAY 0.659574 (-1590 3385);
PAINT MONO (-1590 3385);
DISPLAY INVISIBLE (-1590 3385);
FORCEPROP 1 LASTPIN (-1600 3375) BN 14
J 2
(-1588 3383);
DISPLAY 0.680851 (-1588 3383);
PAINT GREEN (-1588 3383);
FORCEPROP 2 LAST CDS_LIB standard
J 0
(-1650 3375);
DISPLAY INVISIBLE (-1650 3375);
FORCEPROP 1 LAST BODY_TYPE PLUMBING
J 2
(-1650 3425);
DISPLAY 0.872340 (-1650 3425);
PAINT GREEN (-1650 3425);
DISPLAY INVISIBLE (-1650 3425);
FORCEPROP 1 LAST HDL_TAP TRUE
J 2
(-1975 3250);
DISPLAY 0.872340 (-1975 3250);
DISPLAY INVISIBLE (-1975 3250);
FORCEPROP 1 LAST PATH I258
J 2
(-1648 3375);
DISPLAY 0.872340 (-1648 3375);
PAINT GREEN (-1648 3375);
DISPLAY INVISIBLE (-1648 3375);
FORCEADD Q_CAP_DIFFBUS..2
R 2
(-925 2125);
FORCEPROP 1 LAST PART_NUMBER SP_CH4221MEE01
J 2
(-1041 2213);
DISPLAY 0.574468 (-1041 2213);
PAINT GREEN (-1041 2213);
DISPLAY INVISIBLE (-1041 2213);
FORCEPROP 2 LAST VALUE DIFF BUS_0.22UF
J 2
(-1075 2125);
DISPLAY 0.553191 (-1075 2125);
FORCEPROP 1 LAST $LOCATION C1563
J 2
(-675 2150);
DISPLAY 0.723404 (-675 2150);
PAINT GREEN (-675 2150);
FORCEPROP 2 LASTPIN (-850 2125) $PN 1
J 0
(-840 2135);
DISPLAY 0.808511 (-840 2135);
FORCEPROP 2 LASTPIN (-1000 2125) $PN 2
J 2
(-1010 2135);
DISPLAY 0.808511 (-1010 2135);
FORCEPROP 1 LAST CDS_LMAN_SYM_OUTLINE -25,50,25,-50
J 2
(-925 2125);
DISPLAY 0.468085 (-925 2125);
PAINT GREEN (-925 2125);
DISPLAY INVISIBLE (-925 2125);
FORCEPROP 2 LAST CDS_LIB pure_quanta
J 2
(-925 2125);
DISPLAY INVISIBLE (-925 2125);
FORCEPROP 1 LAST PIN_NAMES_ROTATE TRUE
J 2
(-925 2125);
DISPLAY 0.489362 (-925 2125);
PAINT GREEN (-925 2125);
DISPLAY INVISIBLE (-925 2125);
FORCEPROP 2 LAST VOLTAGE 6.3V
J 2
(-1275 2175);
DISPLAY 0.553191 (-1275 2175);
DISPLAY INVISIBLE (-1275 2175);
FORCEPROP 1 LAST MATERIAL X6S
J 2
(-916 2204);
DISPLAY 0.574468 (-916 2204);
PAINT GREEN (-916 2204);
DISPLAY INVISIBLE (-916 2204);
FORCEPROP 2 LAST PACK_TYPE C0201
J 2
(-1100 2175);
DISPLAY 0.553191 (-1100 2175);
DISPLAY INVISIBLE (-1100 2175);
FORCEPROP 2 LAST TOLERANCE 20%
J 2
(-1000 2175);
DISPLAY 0.553191 (-1000 2175);
DISPLAY INVISIBLE (-1000 2175);
FORCEPROP 1 LAST PATH I259
J 2
(-925 2125);
DISPLAY 0.723404 (-925 2125);
DISPLAY INVISIBLE (-925 2125);
FORCEPROP 0 LAST CDS_LOCATION C1563
J 0
(-675 2200);
DISPLAY 1.021277 (-675 2200);
DISPLAY INVISIBLE (-675 2200);
FORCEPROP 2 LAST $SEC 1
J 2
(-750 2200);
DISPLAY 0.680851 (-750 2200);
PAINT MONO (-750 2200);
DISPLAY INVISIBLE (-750 2200);
FORCEPROP 2 LAST CDS_SEC 1
J 2
(-750 2200);
DISPLAY 0.680851 (-750 2200);
DISPLAY INVISIBLE (-750 2200);
FORCEADD Q_CAP_DIFFBUS..2
R 2
(-925 2175);
FORCEPROP 1 LAST PART_NUMBER SP_CH4221MEE01
J 2
(-1041 2263);
DISPLAY 0.574468 (-1041 2263);
PAINT GREEN (-1041 2263);
DISPLAY INVISIBLE (-1041 2263);
FORCEPROP 2 LAST VALUE DIFF BUS_0.22UF
J 2
(-1075 2175);
DISPLAY 0.553191 (-1075 2175);
FORCEPROP 1 LAST $LOCATION C1794
J 2
(-675 2200);
DISPLAY 0.723404 (-675 2200);
PAINT GREEN (-675 2200);
FORCEPROP 2 LASTPIN (-850 2175) $PN 1
J 0
(-840 2185);
DISPLAY 0.808511 (-840 2185);
FORCEPROP 2 LASTPIN (-1000 2175) $PN 2
J 2
(-1010 2185);
DISPLAY 0.808511 (-1010 2185);
FORCEPROP 1 LAST CDS_LMAN_SYM_OUTLINE -25,50,25,-50
J 2
(-925 2175);
DISPLAY 0.468085 (-925 2175);
PAINT GREEN (-925 2175);
DISPLAY INVISIBLE (-925 2175);
FORCEPROP 2 LAST CDS_LIB pure_quanta
J 2
(-925 2175);
DISPLAY INVISIBLE (-925 2175);
FORCEPROP 1 LAST PIN_NAMES_ROTATE TRUE
J 2
(-925 2175);
DISPLAY 0.489362 (-925 2175);
PAINT GREEN (-925 2175);
DISPLAY INVISIBLE (-925 2175);
FORCEPROP 2 LAST VOLTAGE 6.3V
J 2
(-1275 2225);
DISPLAY 0.553191 (-1275 2225);
DISPLAY INVISIBLE (-1275 2225);
FORCEPROP 1 LAST MATERIAL X6S
J 2
(-916 2254);
DISPLAY 0.574468 (-916 2254);
PAINT GREEN (-916 2254);
DISPLAY INVISIBLE (-916 2254);
FORCEPROP 2 LAST PACK_TYPE C0201
J 2
(-1100 2225);
DISPLAY 0.553191 (-1100 2225);
DISPLAY INVISIBLE (-1100 2225);
FORCEPROP 2 LAST TOLERANCE 20%
J 2
(-1000 2225);
DISPLAY 0.553191 (-1000 2225);
DISPLAY INVISIBLE (-1000 2225);
FORCEPROP 1 LAST PATH I260
J 2
(-925 2175);
DISPLAY 0.723404 (-925 2175);
DISPLAY INVISIBLE (-925 2175);
FORCEPROP 0 LAST CDS_LOCATION C1794
J 0
(-675 2250);
DISPLAY 1.021277 (-675 2250);
DISPLAY INVISIBLE (-675 2250);
FORCEPROP 2 LAST $SEC 1
J 2
(-750 2250);
DISPLAY 0.680851 (-750 2250);
PAINT MONO (-750 2250);
DISPLAY INVISIBLE (-750 2250);
FORCEPROP 2 LAST CDS_SEC 1
J 2
(-750 2250);
DISPLAY 0.680851 (-750 2250);
DISPLAY INVISIBLE (-750 2250);
FORCEADD Q_CAP_DIFFBUS..2
R 2
(-925 2325);
FORCEPROP 1 LAST PART_NUMBER SP_CH4221MEE01
J 2
(-1041 2413);
DISPLAY 0.574468 (-1041 2413);
PAINT GREEN (-1041 2413);
DISPLAY INVISIBLE (-1041 2413);
FORCEPROP 2 LAST VALUE DIFF BUS_0.22UF
J 2
(-1075 2325);
DISPLAY 0.553191 (-1075 2325);
FORCEPROP 1 LAST $LOCATION C1793
J 2
(-675 2350);
DISPLAY 0.723404 (-675 2350);
PAINT GREEN (-675 2350);
FORCEPROP 2 LASTPIN (-850 2325) $PN 1
J 0
(-840 2335);
DISPLAY 0.808511 (-840 2335);
FORCEPROP 2 LASTPIN (-1000 2325) $PN 2
J 2
(-1010 2335);
DISPLAY 0.808511 (-1010 2335);
FORCEPROP 1 LAST CDS_LMAN_SYM_OUTLINE -25,50,25,-50
J 2
(-925 2325);
DISPLAY 0.468085 (-925 2325);
PAINT GREEN (-925 2325);
DISPLAY INVISIBLE (-925 2325);
FORCEPROP 2 LAST CDS_LIB pure_quanta
J 2
(-925 2325);
DISPLAY INVISIBLE (-925 2325);
FORCEPROP 1 LAST PIN_NAMES_ROTATE TRUE
J 2
(-925 2325);
DISPLAY 0.489362 (-925 2325);
PAINT GREEN (-925 2325);
DISPLAY INVISIBLE (-925 2325);
FORCEPROP 2 LAST VOLTAGE 6.3V
J 2
(-1275 2375);
DISPLAY 0.553191 (-1275 2375);
DISPLAY INVISIBLE (-1275 2375);
FORCEPROP 1 LAST MATERIAL X6S
J 2
(-916 2404);
DISPLAY 0.574468 (-916 2404);
PAINT GREEN (-916 2404);
DISPLAY INVISIBLE (-916 2404);
FORCEPROP 2 LAST PACK_TYPE C0201
J 2
(-1100 2375);
DISPLAY 0.553191 (-1100 2375);
DISPLAY INVISIBLE (-1100 2375);
FORCEPROP 2 LAST TOLERANCE 20%
J 2
(-1000 2375);
DISPLAY 0.553191 (-1000 2375);
DISPLAY INVISIBLE (-1000 2375);
FORCEPROP 1 LAST PATH I261
J 2
(-925 2325);
DISPLAY 0.723404 (-925 2325);
DISPLAY INVISIBLE (-925 2325);
FORCEPROP 0 LAST CDS_LOCATION C1793
J 0
(-675 2400);
DISPLAY 1.021277 (-675 2400);
DISPLAY INVISIBLE (-675 2400);
FORCEPROP 2 LAST $SEC 1
J 2
(-750 2400);
DISPLAY 0.680851 (-750 2400);
PAINT MONO (-750 2400);
DISPLAY INVISIBLE (-750 2400);
FORCEPROP 2 LAST CDS_SEC 1
J 2
(-750 2400);
DISPLAY 0.680851 (-750 2400);
DISPLAY INVISIBLE (-750 2400);
FORCEADD Q_CAP_DIFFBUS..2
R 2
(-925 2375);
FORCEPROP 1 LAST PART_NUMBER SP_CH4221MEE01
J 2
(-1041 2463);
DISPLAY 0.574468 (-1041 2463);
PAINT GREEN (-1041 2463);
DISPLAY INVISIBLE (-1041 2463);
FORCEPROP 2 LAST VALUE DIFF BUS_0.22UF
J 2
(-1075 2375);
DISPLAY 0.553191 (-1075 2375);
FORCEPROP 1 LAST $LOCATION C1560
J 2
(-675 2400);
DISPLAY 0.723404 (-675 2400);
PAINT GREEN (-675 2400);
FORCEPROP 2 LASTPIN (-850 2375) $PN 1
J 0
(-840 2385);
DISPLAY 0.808511 (-840 2385);
FORCEPROP 2 LASTPIN (-1000 2375) $PN 2
J 2
(-1010 2385);
DISPLAY 0.808511 (-1010 2385);
FORCEPROP 2 LAST CDS_LIB pure_quanta
J 2
(-925 2375);
DISPLAY INVISIBLE (-925 2375);
FORCEPROP 1 LAST CDS_LMAN_SYM_OUTLINE -25,50,25,-50
J 2
(-925 2375);
DISPLAY 0.468085 (-925 2375);
PAINT GREEN (-925 2375);
DISPLAY INVISIBLE (-925 2375);
FORCEPROP 1 LAST PIN_NAMES_ROTATE TRUE
J 2
(-925 2375);
DISPLAY 0.489362 (-925 2375);
PAINT GREEN (-925 2375);
DISPLAY INVISIBLE (-925 2375);
FORCEPROP 2 LAST VOLTAGE 6.3V
J 2
(-1275 2425);
DISPLAY 0.553191 (-1275 2425);
DISPLAY INVISIBLE (-1275 2425);
FORCEPROP 1 LAST MATERIAL X6S
J 2
(-916 2454);
DISPLAY 0.574468 (-916 2454);
PAINT GREEN (-916 2454);
DISPLAY INVISIBLE (-916 2454);
FORCEPROP 2 LAST PACK_TYPE C0201
J 2
(-1100 2425);
DISPLAY 0.553191 (-1100 2425);
DISPLAY INVISIBLE (-1100 2425);
FORCEPROP 2 LAST TOLERANCE 20%
J 2
(-1000 2425);
DISPLAY 0.553191 (-1000 2425);
DISPLAY INVISIBLE (-1000 2425);
FORCEPROP 1 LAST PATH I262
J 2
(-925 2375);
DISPLAY 0.723404 (-925 2375);
DISPLAY INVISIBLE (-925 2375);
FORCEPROP 0 LAST CDS_LOCATION C1560
J 0
(-675 2450);
DISPLAY 1.021277 (-675 2450);
DISPLAY INVISIBLE (-675 2450);
FORCEPROP 2 LAST $SEC 1
J 2
(-750 2450);
DISPLAY 0.680851 (-750 2450);
PAINT MONO (-750 2450);
DISPLAY INVISIBLE (-750 2450);
FORCEPROP 2 LAST CDS_SEC 1
J 2
(-750 2450);
DISPLAY 0.680851 (-750 2450);
DISPLAY INVISIBLE (-750 2450);
FORCEADD Q_CAP_DIFFBUS..2
R 2
(-925 2525);
FORCEPROP 1 LAST PART_NUMBER SP_CH4221MEE01
J 2
(-1041 2613);
DISPLAY 0.574468 (-1041 2613);
PAINT GREEN (-1041 2613);
DISPLAY INVISIBLE (-1041 2613);
FORCEPROP 2 LAST VALUE DIFF BUS_0.22UF
J 2
(-1075 2525);
DISPLAY 0.553191 (-1075 2525);
FORCEPROP 1 LAST $LOCATION C1559
J 2
(-675 2550);
DISPLAY 0.723404 (-675 2550);
PAINT GREEN (-675 2550);
FORCEPROP 2 LASTPIN (-850 2525) $PN 1
J 0
(-840 2535);
DISPLAY 0.808511 (-840 2535);
FORCEPROP 2 LASTPIN (-1000 2525) $PN 2
J 2
(-1010 2535);
DISPLAY 0.808511 (-1010 2535);
FORCEPROP 1 LAST CDS_LMAN_SYM_OUTLINE -25,50,25,-50
J 2
(-925 2525);
DISPLAY 0.468085 (-925 2525);
PAINT GREEN (-925 2525);
DISPLAY INVISIBLE (-925 2525);
FORCEPROP 2 LAST CDS_LIB pure_quanta
J 2
(-925 2525);
DISPLAY INVISIBLE (-925 2525);
FORCEPROP 1 LAST PIN_NAMES_ROTATE TRUE
J 2
(-925 2525);
DISPLAY 0.489362 (-925 2525);
PAINT GREEN (-925 2525);
DISPLAY INVISIBLE (-925 2525);
FORCEPROP 2 LAST VOLTAGE 6.3V
J 2
(-1275 2575);
DISPLAY 0.553191 (-1275 2575);
DISPLAY INVISIBLE (-1275 2575);
FORCEPROP 1 LAST MATERIAL X6S
J 2
(-916 2604);
DISPLAY 0.574468 (-916 2604);
PAINT GREEN (-916 2604);
DISPLAY INVISIBLE (-916 2604);
FORCEPROP 2 LAST PACK_TYPE C0201
J 2
(-1100 2575);
DISPLAY 0.553191 (-1100 2575);
DISPLAY INVISIBLE (-1100 2575);
FORCEPROP 2 LAST TOLERANCE 20%
J 2
(-1000 2575);
DISPLAY 0.553191 (-1000 2575);
DISPLAY INVISIBLE (-1000 2575);
FORCEPROP 1 LAST PATH I263
J 2
(-925 2525);
DISPLAY 0.723404 (-925 2525);
DISPLAY INVISIBLE (-925 2525);
FORCEPROP 0 LAST CDS_LOCATION C1559
J 0
(-675 2600);
DISPLAY 1.021277 (-675 2600);
DISPLAY INVISIBLE (-675 2600);
FORCEPROP 2 LAST $SEC 1
J 2
(-750 2600);
DISPLAY 0.680851 (-750 2600);
PAINT MONO (-750 2600);
DISPLAY INVISIBLE (-750 2600);
FORCEPROP 2 LAST CDS_SEC 1
J 2
(-750 2600);
DISPLAY 0.680851 (-750 2600);
DISPLAY INVISIBLE (-750 2600);
FORCEADD Q_CAP_DIFFBUS..2
R 2
(-925 2575);
FORCEPROP 1 LAST PART_NUMBER SP_CH4221MEE01
J 2
(-1041 2663);
DISPLAY 0.574468 (-1041 2663);
PAINT GREEN (-1041 2663);
DISPLAY INVISIBLE (-1041 2663);
FORCEPROP 2 LAST VALUE DIFF BUS_0.22UF
J 2
(-1075 2575);
DISPLAY 0.553191 (-1075 2575);
FORCEPROP 1 LAST $LOCATION C1558
J 2
(-675 2600);
DISPLAY 0.723404 (-675 2600);
PAINT GREEN (-675 2600);
FORCEPROP 2 LASTPIN (-850 2575) $PN 1
J 0
(-840 2585);
DISPLAY 0.808511 (-840 2585);
FORCEPROP 2 LASTPIN (-1000 2575) $PN 2
J 2
(-1010 2585);
DISPLAY 0.808511 (-1010 2585);
FORCEPROP 1 LAST CDS_LMAN_SYM_OUTLINE -25,50,25,-50
J 2
(-925 2575);
DISPLAY 0.468085 (-925 2575);
PAINT GREEN (-925 2575);
DISPLAY INVISIBLE (-925 2575);
FORCEPROP 2 LAST CDS_LIB pure_quanta
J 2
(-925 2575);
DISPLAY INVISIBLE (-925 2575);
FORCEPROP 1 LAST PIN_NAMES_ROTATE TRUE
J 2
(-925 2575);
DISPLAY 0.489362 (-925 2575);
PAINT GREEN (-925 2575);
DISPLAY INVISIBLE (-925 2575);
FORCEPROP 2 LAST VOLTAGE 6.3V
J 2
(-1275 2625);
DISPLAY 0.553191 (-1275 2625);
DISPLAY INVISIBLE (-1275 2625);
FORCEPROP 1 LAST MATERIAL X6S
J 2
(-916 2654);
DISPLAY 0.574468 (-916 2654);
PAINT GREEN (-916 2654);
DISPLAY INVISIBLE (-916 2654);
FORCEPROP 2 LAST PACK_TYPE C0201
J 2
(-1100 2625);
DISPLAY 0.553191 (-1100 2625);
DISPLAY INVISIBLE (-1100 2625);
FORCEPROP 2 LAST TOLERANCE 20%
J 2
(-1000 2625);
DISPLAY 0.553191 (-1000 2625);
DISPLAY INVISIBLE (-1000 2625);
FORCEPROP 1 LAST PATH I264
J 2
(-925 2575);
DISPLAY 0.723404 (-925 2575);
DISPLAY INVISIBLE (-925 2575);
FORCEPROP 0 LAST CDS_LOCATION C1558
J 0
(-675 2650);
DISPLAY 1.021277 (-675 2650);
DISPLAY INVISIBLE (-675 2650);
FORCEPROP 2 LAST $SEC 1
J 2
(-750 2650);
DISPLAY 0.680851 (-750 2650);
PAINT MONO (-750 2650);
DISPLAY INVISIBLE (-750 2650);
FORCEPROP 2 LAST CDS_SEC 1
J 2
(-750 2650);
DISPLAY 0.680851 (-750 2650);
DISPLAY INVISIBLE (-750 2650);
FORCEADD Q_CAP_DIFFBUS..2
R 2
(-925 2775);
FORCEPROP 1 LAST PART_NUMBER SP_CH4221MEE01
J 2
(-1041 2863);
DISPLAY 0.574468 (-1041 2863);
PAINT GREEN (-1041 2863);
DISPLAY INVISIBLE (-1041 2863);
FORCEPROP 2 LAST VALUE DIFF BUS_0.22UF
J 2
(-1075 2775);
DISPLAY 0.553191 (-1075 2775);
FORCEPROP 1 LAST $LOCATION C1556
J 2
(-675 2800);
DISPLAY 0.723404 (-675 2800);
PAINT GREEN (-675 2800);
FORCEPROP 2 LASTPIN (-850 2775) $PN 1
J 0
(-840 2785);
DISPLAY 0.808511 (-840 2785);
FORCEPROP 2 LASTPIN (-1000 2775) $PN 2
J 2
(-1010 2785);
DISPLAY 0.808511 (-1010 2785);
FORCEPROP 2 LAST CDS_LIB pure_quanta
J 2
(-925 2775);
DISPLAY INVISIBLE (-925 2775);
FORCEPROP 1 LAST CDS_LMAN_SYM_OUTLINE -25,50,25,-50
J 2
(-925 2775);
DISPLAY 0.468085 (-925 2775);
PAINT GREEN (-925 2775);
DISPLAY INVISIBLE (-925 2775);
FORCEPROP 1 LAST PIN_NAMES_ROTATE TRUE
J 2
(-925 2775);
DISPLAY 0.489362 (-925 2775);
PAINT GREEN (-925 2775);
DISPLAY INVISIBLE (-925 2775);
FORCEPROP 2 LAST VOLTAGE 6.3V
J 2
(-1275 2825);
DISPLAY 0.553191 (-1275 2825);
DISPLAY INVISIBLE (-1275 2825);
FORCEPROP 1 LAST MATERIAL X6S
J 2
(-916 2854);
DISPLAY 0.574468 (-916 2854);
PAINT GREEN (-916 2854);
DISPLAY INVISIBLE (-916 2854);
FORCEPROP 2 LAST PACK_TYPE C0201
J 2
(-1100 2825);
DISPLAY 0.553191 (-1100 2825);
DISPLAY INVISIBLE (-1100 2825);
FORCEPROP 2 LAST TOLERANCE 20%
J 2
(-1000 2825);
DISPLAY 0.553191 (-1000 2825);
DISPLAY INVISIBLE (-1000 2825);
FORCEPROP 1 LAST PATH I265
J 2
(-925 2775);
DISPLAY 0.723404 (-925 2775);
DISPLAY INVISIBLE (-925 2775);
FORCEPROP 0 LAST CDS_LOCATION C1556
J 0
(-675 2850);
DISPLAY 1.021277 (-675 2850);
DISPLAY INVISIBLE (-675 2850);
FORCEPROP 2 LAST $SEC 1
J 2
(-750 2850);
DISPLAY 0.680851 (-750 2850);
PAINT MONO (-750 2850);
DISPLAY INVISIBLE (-750 2850);
FORCEPROP 2 LAST CDS_SEC 1
J 2
(-750 2850);
DISPLAY 0.680851 (-750 2850);
DISPLAY INVISIBLE (-750 2850);
FORCEADD Q_CAP_DIFFBUS..2
R 2
(-925 2725);
FORCEPROP 1 LAST PART_NUMBER SP_CH4221MEE01
J 2
(-1041 2813);
DISPLAY 0.574468 (-1041 2813);
PAINT GREEN (-1041 2813);
DISPLAY INVISIBLE (-1041 2813);
FORCEPROP 2 LAST VALUE DIFF BUS_0.22UF
J 2
(-1075 2725);
DISPLAY 0.553191 (-1075 2725);
FORCEPROP 1 LAST $LOCATION C1557
J 2
(-675 2750);
DISPLAY 0.723404 (-675 2750);
PAINT GREEN (-675 2750);
FORCEPROP 2 LASTPIN (-850 2725) $PN 1
J 0
(-840 2735);
DISPLAY 0.808511 (-840 2735);
FORCEPROP 2 LASTPIN (-1000 2725) $PN 2
J 2
(-1010 2735);
DISPLAY 0.808511 (-1010 2735);
FORCEPROP 2 LAST CDS_LIB pure_quanta
J 2
(-925 2725);
DISPLAY INVISIBLE (-925 2725);
FORCEPROP 1 LAST CDS_LMAN_SYM_OUTLINE -25,50,25,-50
J 2
(-925 2725);
DISPLAY 0.468085 (-925 2725);
PAINT GREEN (-925 2725);
DISPLAY INVISIBLE (-925 2725);
FORCEPROP 1 LAST PIN_NAMES_ROTATE TRUE
J 2
(-925 2725);
DISPLAY 0.489362 (-925 2725);
PAINT GREEN (-925 2725);
DISPLAY INVISIBLE (-925 2725);
FORCEPROP 2 LAST VOLTAGE 6.3V
J 2
(-1275 2775);
DISPLAY 0.553191 (-1275 2775);
DISPLAY INVISIBLE (-1275 2775);
FORCEPROP 1 LAST MATERIAL X6S
J 2
(-916 2804);
DISPLAY 0.574468 (-916 2804);
PAINT GREEN (-916 2804);
DISPLAY INVISIBLE (-916 2804);
FORCEPROP 2 LAST PACK_TYPE C0201
J 2
(-1100 2775);
DISPLAY 0.553191 (-1100 2775);
DISPLAY INVISIBLE (-1100 2775);
FORCEPROP 2 LAST TOLERANCE 20%
J 2
(-1000 2775);
DISPLAY 0.553191 (-1000 2775);
DISPLAY INVISIBLE (-1000 2775);
FORCEPROP 1 LAST PATH I266
J 2
(-925 2725);
DISPLAY 0.723404 (-925 2725);
DISPLAY INVISIBLE (-925 2725);
FORCEPROP 0 LAST CDS_LOCATION C1557
J 0
(-675 2800);
DISPLAY 1.021277 (-675 2800);
DISPLAY INVISIBLE (-675 2800);
FORCEPROP 2 LAST $SEC 1
J 2
(-750 2800);
DISPLAY 0.680851 (-750 2800);
PAINT MONO (-750 2800);
DISPLAY INVISIBLE (-750 2800);
FORCEPROP 2 LAST CDS_SEC 1
J 2
(-750 2800);
DISPLAY 0.680851 (-750 2800);
DISPLAY INVISIBLE (-750 2800);
FORCEADD Q_CAP_DIFFBUS..2
R 2
(-925 2925);
FORCEPROP 1 LAST PART_NUMBER SP_CH4221MEE01
J 2
(-1041 3013);
DISPLAY 0.574468 (-1041 3013);
PAINT GREEN (-1041 3013);
DISPLAY INVISIBLE (-1041 3013);
FORCEPROP 2 LAST VALUE DIFF BUS_0.22UF
J 2
(-1075 2925);
DISPLAY 0.553191 (-1075 2925);
FORCEPROP 1 LAST $LOCATION C1555
J 2
(-675 2950);
DISPLAY 0.723404 (-675 2950);
PAINT GREEN (-675 2950);
FORCEPROP 2 LASTPIN (-850 2925) $PN 1
J 0
(-840 2935);
DISPLAY 0.808511 (-840 2935);
FORCEPROP 2 LASTPIN (-1000 2925) $PN 2
J 2
(-1010 2935);
DISPLAY 0.808511 (-1010 2935);
FORCEPROP 1 LAST CDS_LMAN_SYM_OUTLINE -25,50,25,-50
J 2
(-925 2925);
DISPLAY 0.468085 (-925 2925);
PAINT GREEN (-925 2925);
DISPLAY INVISIBLE (-925 2925);
FORCEPROP 2 LAST CDS_LIB pure_quanta
J 2
(-925 2925);
DISPLAY INVISIBLE (-925 2925);
FORCEPROP 1 LAST PIN_NAMES_ROTATE TRUE
J 2
(-925 2925);
DISPLAY 0.489362 (-925 2925);
PAINT GREEN (-925 2925);
DISPLAY INVISIBLE (-925 2925);
FORCEPROP 2 LAST VOLTAGE 6.3V
J 2
(-1275 2975);
DISPLAY 0.553191 (-1275 2975);
DISPLAY INVISIBLE (-1275 2975);
FORCEPROP 1 LAST MATERIAL X6S
J 2
(-916 3004);
DISPLAY 0.574468 (-916 3004);
PAINT GREEN (-916 3004);
DISPLAY INVISIBLE (-916 3004);
FORCEPROP 2 LAST PACK_TYPE C0201
J 2
(-1100 2975);
DISPLAY 0.553191 (-1100 2975);
DISPLAY INVISIBLE (-1100 2975);
FORCEPROP 2 LAST TOLERANCE 20%
J 2
(-1000 2975);
DISPLAY 0.553191 (-1000 2975);
DISPLAY INVISIBLE (-1000 2975);
FORCEPROP 1 LAST PATH I267
J 2
(-925 2925);
DISPLAY 0.723404 (-925 2925);
DISPLAY INVISIBLE (-925 2925);
FORCEPROP 0 LAST CDS_LOCATION C1555
J 0
(-675 3000);
DISPLAY 1.021277 (-675 3000);
DISPLAY INVISIBLE (-675 3000);
FORCEPROP 2 LAST $SEC 1
J 2
(-750 3000);
DISPLAY 0.680851 (-750 3000);
PAINT MONO (-750 3000);
DISPLAY INVISIBLE (-750 3000);
FORCEPROP 2 LAST CDS_SEC 1
J 2
(-750 3000);
DISPLAY 0.680851 (-750 3000);
DISPLAY INVISIBLE (-750 3000);
FORCEADD Q_CAP_DIFFBUS..2
R 2
(-925 2975);
FORCEPROP 1 LAST PART_NUMBER SP_CH4221MEE01
J 2
(-1041 3063);
DISPLAY 0.574468 (-1041 3063);
PAINT GREEN (-1041 3063);
DISPLAY INVISIBLE (-1041 3063);
FORCEPROP 2 LAST VALUE DIFF BUS_0.22UF
J 2
(-1075 2975);
DISPLAY 0.553191 (-1075 2975);
FORCEPROP 1 LAST $LOCATION C1554
J 2
(-675 3000);
DISPLAY 0.723404 (-675 3000);
PAINT GREEN (-675 3000);
FORCEPROP 2 LASTPIN (-850 2975) $PN 1
J 0
(-840 2985);
DISPLAY 0.808511 (-840 2985);
FORCEPROP 2 LASTPIN (-1000 2975) $PN 2
J 2
(-1010 2985);
DISPLAY 0.808511 (-1010 2985);
FORCEPROP 1 LAST CDS_LMAN_SYM_OUTLINE -25,50,25,-50
J 2
(-925 2975);
DISPLAY 0.468085 (-925 2975);
PAINT GREEN (-925 2975);
DISPLAY INVISIBLE (-925 2975);
FORCEPROP 2 LAST CDS_LIB pure_quanta
J 2
(-925 2975);
DISPLAY INVISIBLE (-925 2975);
FORCEPROP 1 LAST PIN_NAMES_ROTATE TRUE
J 2
(-925 2975);
DISPLAY 0.489362 (-925 2975);
PAINT GREEN (-925 2975);
DISPLAY INVISIBLE (-925 2975);
FORCEPROP 2 LAST VOLTAGE 6.3V
J 2
(-1275 3025);
DISPLAY 0.553191 (-1275 3025);
DISPLAY INVISIBLE (-1275 3025);
FORCEPROP 1 LAST MATERIAL X6S
J 2
(-916 3054);
DISPLAY 0.574468 (-916 3054);
PAINT GREEN (-916 3054);
DISPLAY INVISIBLE (-916 3054);
FORCEPROP 2 LAST PACK_TYPE C0201
J 2
(-1100 3025);
DISPLAY 0.553191 (-1100 3025);
DISPLAY INVISIBLE (-1100 3025);
FORCEPROP 2 LAST TOLERANCE 20%
J 2
(-1000 3025);
DISPLAY 0.553191 (-1000 3025);
DISPLAY INVISIBLE (-1000 3025);
FORCEPROP 1 LAST PATH I268
J 2
(-925 2975);
DISPLAY 0.723404 (-925 2975);
DISPLAY INVISIBLE (-925 2975);
FORCEPROP 0 LAST CDS_LOCATION C1554
J 0
(-675 3050);
DISPLAY 1.021277 (-675 3050);
DISPLAY INVISIBLE (-675 3050);
FORCEPROP 2 LAST $SEC 1
J 2
(-750 3050);
DISPLAY 0.680851 (-750 3050);
PAINT MONO (-750 3050);
DISPLAY INVISIBLE (-750 3050);
FORCEPROP 2 LAST CDS_SEC 1
J 2
(-750 3050);
DISPLAY 0.680851 (-750 3050);
DISPLAY INVISIBLE (-750 3050);
FORCEADD Q_CAP_DIFFBUS..2
R 2
(-925 3125);
FORCEPROP 1 LAST PART_NUMBER SP_CH4221MEE01
J 2
(-1041 3213);
DISPLAY 0.574468 (-1041 3213);
PAINT GREEN (-1041 3213);
DISPLAY INVISIBLE (-1041 3213);
FORCEPROP 2 LAST VALUE DIFF BUS_0.22UF
J 2
(-1075 3125);
DISPLAY 0.553191 (-1075 3125);
FORCEPROP 1 LAST $LOCATION C1553
J 2
(-675 3150);
DISPLAY 0.723404 (-675 3150);
PAINT GREEN (-675 3150);
FORCEPROP 2 LASTPIN (-850 3125) $PN 1
J 0
(-840 3135);
DISPLAY 0.808511 (-840 3135);
FORCEPROP 2 LASTPIN (-1000 3125) $PN 2
J 2
(-1010 3135);
DISPLAY 0.808511 (-1010 3135);
FORCEPROP 1 LAST CDS_LMAN_SYM_OUTLINE -25,50,25,-50
J 2
(-925 3125);
DISPLAY 0.468085 (-925 3125);
PAINT GREEN (-925 3125);
DISPLAY INVISIBLE (-925 3125);
FORCEPROP 2 LAST CDS_LIB pure_quanta
J 2
(-925 3125);
DISPLAY INVISIBLE (-925 3125);
FORCEPROP 1 LAST PIN_NAMES_ROTATE TRUE
J 2
(-925 3125);
DISPLAY 0.489362 (-925 3125);
PAINT GREEN (-925 3125);
DISPLAY INVISIBLE (-925 3125);
FORCEPROP 2 LAST VOLTAGE 6.3V
J 2
(-1275 3175);
DISPLAY 0.553191 (-1275 3175);
DISPLAY INVISIBLE (-1275 3175);
FORCEPROP 1 LAST MATERIAL X6S
J 2
(-916 3204);
DISPLAY 0.574468 (-916 3204);
PAINT GREEN (-916 3204);
DISPLAY INVISIBLE (-916 3204);
FORCEPROP 2 LAST PACK_TYPE C0201
J 2
(-1100 3175);
DISPLAY 0.553191 (-1100 3175);
DISPLAY INVISIBLE (-1100 3175);
FORCEPROP 2 LAST TOLERANCE 20%
J 2
(-1000 3175);
DISPLAY 0.553191 (-1000 3175);
DISPLAY INVISIBLE (-1000 3175);
FORCEPROP 1 LAST PATH I269
J 2
(-925 3125);
DISPLAY 0.723404 (-925 3125);
DISPLAY INVISIBLE (-925 3125);
FORCEPROP 0 LAST CDS_LOCATION C1553
J 0
(-675 3200);
DISPLAY 1.021277 (-675 3200);
DISPLAY INVISIBLE (-675 3200);
FORCEPROP 2 LAST $SEC 1
J 2
(-750 3200);
DISPLAY 0.680851 (-750 3200);
PAINT MONO (-750 3200);
DISPLAY INVISIBLE (-750 3200);
FORCEPROP 2 LAST CDS_SEC 1
J 2
(-750 3200);
DISPLAY 0.680851 (-750 3200);
DISPLAY INVISIBLE (-750 3200);
FORCEADD Q_CAP_DIFFBUS..2
R 2
(-925 3175);
FORCEPROP 1 LAST PART_NUMBER SP_CH4221MEE01
J 2
(-1041 3263);
DISPLAY 0.574468 (-1041 3263);
PAINT GREEN (-1041 3263);
DISPLAY INVISIBLE (-1041 3263);
FORCEPROP 2 LAST VALUE DIFF BUS_0.22UF
J 2
(-1075 3175);
DISPLAY 0.553191 (-1075 3175);
FORCEPROP 1 LAST $LOCATION C1552
J 2
(-675 3200);
DISPLAY 0.723404 (-675 3200);
PAINT GREEN (-675 3200);
FORCEPROP 2 LASTPIN (-850 3175) $PN 1
J 0
(-840 3185);
DISPLAY 0.808511 (-840 3185);
FORCEPROP 2 LASTPIN (-1000 3175) $PN 2
J 2
(-1010 3185);
DISPLAY 0.808511 (-1010 3185);
FORCEPROP 1 LAST CDS_LMAN_SYM_OUTLINE -25,50,25,-50
J 2
(-925 3175);
DISPLAY 0.468085 (-925 3175);
PAINT GREEN (-925 3175);
DISPLAY INVISIBLE (-925 3175);
FORCEPROP 2 LAST CDS_LIB pure_quanta
J 2
(-925 3175);
DISPLAY INVISIBLE (-925 3175);
FORCEPROP 1 LAST PIN_NAMES_ROTATE TRUE
J 2
(-925 3175);
DISPLAY 0.489362 (-925 3175);
PAINT GREEN (-925 3175);
DISPLAY INVISIBLE (-925 3175);
FORCEPROP 2 LAST VOLTAGE 6.3V
J 2
(-1275 3225);
DISPLAY 0.553191 (-1275 3225);
DISPLAY INVISIBLE (-1275 3225);
FORCEPROP 1 LAST MATERIAL X6S
J 2
(-916 3254);
DISPLAY 0.574468 (-916 3254);
PAINT GREEN (-916 3254);
DISPLAY INVISIBLE (-916 3254);
FORCEPROP 2 LAST PACK_TYPE C0201
J 2
(-1100 3225);
DISPLAY 0.553191 (-1100 3225);
DISPLAY INVISIBLE (-1100 3225);
FORCEPROP 2 LAST TOLERANCE 20%
J 2
(-1000 3225);
DISPLAY 0.553191 (-1000 3225);
DISPLAY INVISIBLE (-1000 3225);
FORCEPROP 1 LAST PATH I270
J 2
(-925 3175);
DISPLAY 0.723404 (-925 3175);
DISPLAY INVISIBLE (-925 3175);
FORCEPROP 0 LAST CDS_LOCATION C1552
J 0
(-675 3250);
DISPLAY 1.021277 (-675 3250);
DISPLAY INVISIBLE (-675 3250);
FORCEPROP 2 LAST $SEC 1
J 2
(-750 3250);
DISPLAY 0.680851 (-750 3250);
PAINT MONO (-750 3250);
DISPLAY INVISIBLE (-750 3250);
FORCEPROP 2 LAST CDS_SEC 1
J 2
(-750 3250);
DISPLAY 0.680851 (-750 3250);
DISPLAY INVISIBLE (-750 3250);
FORCEADD Q_CAP_DIFFBUS..2
R 2
(-925 3325);
FORCEPROP 1 LAST PART_NUMBER SP_CH4221MEE01
J 2
(-1041 3413);
DISPLAY 0.574468 (-1041 3413);
PAINT GREEN (-1041 3413);
DISPLAY INVISIBLE (-1041 3413);
FORCEPROP 2 LAST VALUE DIFF BUS_0.22UF
J 2
(-1075 3325);
DISPLAY 0.553191 (-1075 3325);
FORCEPROP 1 LAST $LOCATION C1792
J 2
(-675 3350);
DISPLAY 0.723404 (-675 3350);
PAINT GREEN (-675 3350);
FORCEPROP 2 LASTPIN (-850 3325) $PN 1
J 0
(-840 3335);
DISPLAY 0.808511 (-840 3335);
FORCEPROP 2 LASTPIN (-1000 3325) $PN 2
J 2
(-1010 3335);
DISPLAY 0.808511 (-1010 3335);
FORCEPROP 1 LAST CDS_LMAN_SYM_OUTLINE -25,50,25,-50
J 2
(-925 3325);
DISPLAY 0.468085 (-925 3325);
PAINT GREEN (-925 3325);
DISPLAY INVISIBLE (-925 3325);
FORCEPROP 2 LAST CDS_LIB pure_quanta
J 2
(-925 3325);
DISPLAY INVISIBLE (-925 3325);
FORCEPROP 1 LAST PIN_NAMES_ROTATE TRUE
J 2
(-925 3325);
DISPLAY 0.489362 (-925 3325);
PAINT GREEN (-925 3325);
DISPLAY INVISIBLE (-925 3325);
FORCEPROP 2 LAST VOLTAGE 6.3V
J 2
(-1275 3375);
DISPLAY 0.553191 (-1275 3375);
DISPLAY INVISIBLE (-1275 3375);
FORCEPROP 1 LAST MATERIAL X6S
J 2
(-916 3404);
DISPLAY 0.574468 (-916 3404);
PAINT GREEN (-916 3404);
DISPLAY INVISIBLE (-916 3404);
FORCEPROP 2 LAST PACK_TYPE C0201
J 2
(-1100 3375);
DISPLAY 0.553191 (-1100 3375);
DISPLAY INVISIBLE (-1100 3375);
FORCEPROP 2 LAST TOLERANCE 20%
J 2
(-1000 3375);
DISPLAY 0.553191 (-1000 3375);
DISPLAY INVISIBLE (-1000 3375);
FORCEPROP 1 LAST PATH I271
J 2
(-925 3325);
DISPLAY 0.723404 (-925 3325);
DISPLAY INVISIBLE (-925 3325);
FORCEPROP 0 LAST CDS_LOCATION C1792
J 0
(-675 3400);
DISPLAY 1.021277 (-675 3400);
DISPLAY INVISIBLE (-675 3400);
FORCEPROP 2 LAST $SEC 1
J 2
(-750 3400);
DISPLAY 0.680851 (-750 3400);
PAINT MONO (-750 3400);
DISPLAY INVISIBLE (-750 3400);
FORCEPROP 2 LAST CDS_SEC 1
J 2
(-750 3400);
DISPLAY 0.680851 (-750 3400);
DISPLAY INVISIBLE (-750 3400);
FORCEADD Q_CAP_DIFFBUS..2
R 2
(-925 3375);
FORCEPROP 1 LAST PART_NUMBER SP_CH4221MEE01
J 2
(-1041 3463);
DISPLAY 0.574468 (-1041 3463);
PAINT GREEN (-1041 3463);
DISPLAY INVISIBLE (-1041 3463);
FORCEPROP 2 LAST VALUE DIFF BUS_0.22UF
J 2
(-1075 3375);
DISPLAY 0.553191 (-1075 3375);
FORCEPROP 1 LAST $LOCATION C1550
J 2
(-675 3400);
DISPLAY 0.723404 (-675 3400);
PAINT GREEN (-675 3400);
FORCEPROP 2 LASTPIN (-850 3375) $PN 1
J 0
(-840 3385);
DISPLAY 0.808511 (-840 3385);
FORCEPROP 2 LASTPIN (-1000 3375) $PN 2
J 2
(-1010 3385);
DISPLAY 0.808511 (-1010 3385);
FORCEPROP 1 LAST CDS_LMAN_SYM_OUTLINE -25,50,25,-50
J 2
(-925 3375);
DISPLAY 0.468085 (-925 3375);
PAINT GREEN (-925 3375);
DISPLAY INVISIBLE (-925 3375);
FORCEPROP 2 LAST CDS_LIB pure_quanta
J 2
(-925 3375);
DISPLAY INVISIBLE (-925 3375);
FORCEPROP 1 LAST PIN_NAMES_ROTATE TRUE
J 2
(-925 3375);
DISPLAY 0.489362 (-925 3375);
PAINT GREEN (-925 3375);
DISPLAY INVISIBLE (-925 3375);
FORCEPROP 2 LAST VOLTAGE 6.3V
J 2
(-1275 3425);
DISPLAY 0.553191 (-1275 3425);
DISPLAY INVISIBLE (-1275 3425);
FORCEPROP 1 LAST MATERIAL X6S
J 2
(-916 3454);
DISPLAY 0.574468 (-916 3454);
PAINT GREEN (-916 3454);
DISPLAY INVISIBLE (-916 3454);
FORCEPROP 2 LAST PACK_TYPE C0201
J 2
(-1100 3425);
DISPLAY 0.553191 (-1100 3425);
DISPLAY INVISIBLE (-1100 3425);
FORCEPROP 2 LAST TOLERANCE 20%
J 2
(-1000 3425);
DISPLAY 0.553191 (-1000 3425);
DISPLAY INVISIBLE (-1000 3425);
FORCEPROP 1 LAST PATH I272
J 2
(-925 3375);
DISPLAY 0.723404 (-925 3375);
DISPLAY INVISIBLE (-925 3375);
FORCEPROP 0 LAST CDS_LOCATION C1550
J 0
(-675 3450);
DISPLAY 1.021277 (-675 3450);
DISPLAY INVISIBLE (-675 3450);
FORCEPROP 2 LAST $SEC 1
J 2
(-750 3450);
DISPLAY 0.680851 (-750 3450);
PAINT MONO (-750 3450);
DISPLAY INVISIBLE (-750 3450);
FORCEPROP 2 LAST CDS_SEC 1
J 2
(-750 3450);
DISPLAY 0.680851 (-750 3450);
DISPLAY INVISIBLE (-750 3450);
FORCEADD Q_CAP_DIFFBUS..2
R 2
(-925 3575);
FORCEPROP 1 LAST PART_NUMBER SP_CH4221MEE01
J 2
(-666 3663);
DISPLAY 0.574468 (-666 3663);
PAINT GREEN (-666 3663);
DISPLAY INVISIBLE (-666 3663);
FORCEPROP 2 LAST PACK_TYPE C0201
J 2
(-925 3725);
DISPLAY 0.553191 (-925 3725);
PAINT GREEN (-925 3725);
FORCEPROP 2 LAST VALUE DIFF BUS_0.22UF
J 2
(-1075 3575);
DISPLAY 0.553191 (-1075 3575);
FORCEPROP 2 LAST VOLTAGE 6.3V
J 2
(-675 3725);
DISPLAY 0.553191 (-675 3725);
PAINT GREEN (-675 3725);
FORCEPROP 1 LAST MATERIAL X6S
J 2
(-966 3779);
DISPLAY 0.574468 (-966 3779);
PAINT GREEN (-966 3779);
FORCEPROP 2 LAST TOLERANCE 20%
J 2
(-825 3725);
DISPLAY 0.553191 (-825 3725);
PAINT GREEN (-825 3725);
FORCEPROP 1 LAST $LOCATION C1548
J 2
(-675 3600);
DISPLAY 0.723404 (-675 3600);
PAINT GREEN (-675 3600);
FORCEPROP 2 LASTPIN (-850 3575) $PN 1
J 0
(-840 3585);
DISPLAY 0.808511 (-840 3585);
FORCEPROP 2 LASTPIN (-1000 3575) $PN 2
J 2
(-1010 3585);
DISPLAY 0.808511 (-1010 3585);
FORCEPROP 2 LAST CDS_LIB pure_quanta
J 2
(-925 3575);
DISPLAY INVISIBLE (-925 3575);
FORCEPROP 1 LAST CDS_LMAN_SYM_OUTLINE -25,50,25,-50
J 2
(-925 3575);
DISPLAY 0.468085 (-925 3575);
PAINT GREEN (-925 3575);
DISPLAY INVISIBLE (-925 3575);
FORCEPROP 1 LAST PIN_NAMES_ROTATE TRUE
J 2
(-925 3575);
DISPLAY 0.489362 (-925 3575);
PAINT GREEN (-925 3575);
DISPLAY INVISIBLE (-925 3575);
FORCEPROP 1 LAST PATH I273
J 2
(-925 3575);
DISPLAY 0.723404 (-925 3575);
DISPLAY INVISIBLE (-925 3575);
FORCEPROP 0 LAST CDS_LOCATION C1548
J 0
(-950 3825);
DISPLAY 1.021277 (-950 3825);
DISPLAY INVISIBLE (-950 3825);
FORCEPROP 2 LAST $SEC 1
J 2
(-750 3650);
DISPLAY 0.680851 (-750 3650);
PAINT MONO (-750 3650);
DISPLAY INVISIBLE (-750 3650);
FORCEPROP 2 LAST CDS_SEC 1
J 2
(-750 3650);
DISPLAY 0.680851 (-750 3650);
DISPLAY INVISIBLE (-750 3650);
FORCEADD Q_CAP_DIFFBUS..2
R 2
(-925 3525);
FORCEPROP 1 LAST PART_NUMBER SP_CH4221MEE01
J 2
(-1041 3613);
DISPLAY 0.574468 (-1041 3613);
PAINT GREEN (-1041 3613);
DISPLAY INVISIBLE (-1041 3613);
FORCEPROP 2 LAST VALUE DIFF BUS_0.22UF
J 2
(-1075 3525);
DISPLAY 0.553191 (-1075 3525);
FORCEPROP 1 LAST $LOCATION C1549
J 2
(-675 3550);
DISPLAY 0.723404 (-675 3550);
PAINT GREEN (-675 3550);
FORCEPROP 2 LASTPIN (-850 3525) $PN 1
J 0
(-840 3535);
DISPLAY 0.808511 (-840 3535);
FORCEPROP 2 LASTPIN (-1000 3525) $PN 2
J 2
(-1010 3535);
DISPLAY 0.808511 (-1010 3535);
FORCEPROP 1 LAST CDS_LMAN_SYM_OUTLINE -25,50,25,-50
J 2
(-925 3525);
DISPLAY 0.468085 (-925 3525);
PAINT GREEN (-925 3525);
DISPLAY INVISIBLE (-925 3525);
FORCEPROP 2 LAST CDS_LIB pure_quanta
J 2
(-925 3525);
DISPLAY INVISIBLE (-925 3525);
FORCEPROP 1 LAST PIN_NAMES_ROTATE TRUE
J 2
(-925 3525);
DISPLAY 0.489362 (-925 3525);
PAINT GREEN (-925 3525);
DISPLAY INVISIBLE (-925 3525);
FORCEPROP 2 LAST VOLTAGE 6.3V
J 2
(-1275 3575);
DISPLAY 0.553191 (-1275 3575);
DISPLAY INVISIBLE (-1275 3575);
FORCEPROP 1 LAST MATERIAL X6S
J 2
(-916 3604);
DISPLAY 0.574468 (-916 3604);
PAINT GREEN (-916 3604);
DISPLAY INVISIBLE (-916 3604);
FORCEPROP 2 LAST PACK_TYPE C0201
J 2
(-1100 3575);
DISPLAY 0.553191 (-1100 3575);
DISPLAY INVISIBLE (-1100 3575);
FORCEPROP 2 LAST TOLERANCE 20%
J 2
(-1000 3575);
DISPLAY 0.553191 (-1000 3575);
DISPLAY INVISIBLE (-1000 3575);
FORCEPROP 1 LAST PATH I274
J 2
(-925 3525);
DISPLAY 0.723404 (-925 3525);
DISPLAY INVISIBLE (-925 3525);
FORCEPROP 0 LAST CDS_LOCATION C1549
J 0
(-675 3600);
DISPLAY 1.021277 (-675 3600);
DISPLAY INVISIBLE (-675 3600);
FORCEPROP 2 LAST $SEC 1
J 2
(-750 3600);
DISPLAY 0.680851 (-750 3600);
PAINT MONO (-750 3600);
DISPLAY INVISIBLE (-750 3600);
FORCEPROP 2 LAST CDS_SEC 1
J 2
(-750 3600);
DISPLAY 0.680851 (-750 3600);
DISPLAY INVISIBLE (-750 3600);
FORCEADD TAP..1
(-375 200);
FORCEPROP 3 LASTPIN (-425 200) SIG_NAME P5E_CPU0_PE4_TX_C_DN<0>
J 0
(-415 210);
DISPLAY 0.659574 (-415 210);
PAINT MONO (-415 210);
DISPLAY INVISIBLE (-415 210);
FORCEPROP 1 LASTPIN (-425 200) BN 0
J 0
(-437 208);
DISPLAY 0.680851 (-437 208);
PAINT GREEN (-437 208);
FORCEPROP 2 LAST CDS_LIB standard
J 0
(-375 200);
DISPLAY INVISIBLE (-375 200);
FORCEPROP 1 LAST BODY_TYPE PLUMBING
J 0
(-375 250);
DISPLAY 0.872340 (-375 250);
PAINT GREEN (-375 250);
DISPLAY INVISIBLE (-375 250);
FORCEPROP 1 LAST HDL_TAP TRUE
J 0
(-50 75);
DISPLAY 0.872340 (-50 75);
DISPLAY INVISIBLE (-50 75);
FORCEPROP 1 LAST PATH I275
J 0
(-377 200);
DISPLAY 0.872340 (-377 200);
PAINT GREEN (-377 200);
DISPLAY INVISIBLE (-377 200);
FORCEADD TAP..1
(-175 150);
FORCEPROP 3 LASTPIN (-225 150) SIG_NAME P5E_CPU0_PE4_TX_C_DP<0>
J 0
(-215 160);
DISPLAY 0.659574 (-215 160);
PAINT MONO (-215 160);
DISPLAY INVISIBLE (-215 160);
FORCEPROP 1 LASTPIN (-225 150) BN 0
J 0
(-237 158);
DISPLAY 0.680851 (-237 158);
PAINT GREEN (-237 158);
FORCEPROP 2 LAST CDS_LIB standard
J 0
(-175 150);
DISPLAY INVISIBLE (-175 150);
FORCEPROP 1 LAST BODY_TYPE PLUMBING
J 0
(-175 200);
DISPLAY 0.872340 (-175 200);
PAINT GREEN (-175 200);
DISPLAY INVISIBLE (-175 200);
FORCEPROP 1 LAST HDL_TAP TRUE
J 0
(150 25);
DISPLAY 0.872340 (150 25);
DISPLAY INVISIBLE (150 25);
FORCEPROP 1 LAST PATH I276
J 0
(-177 150);
DISPLAY 0.872340 (-177 150);
PAINT GREEN (-177 150);
DISPLAY INVISIBLE (-177 150);
FORCEADD TAP..1
(-175 350);
FORCEPROP 3 LASTPIN (-225 350) SIG_NAME P5E_CPU0_PE4_TX_C_DP<1>
J 0
(-215 360);
DISPLAY 0.659574 (-215 360);
PAINT MONO (-215 360);
DISPLAY INVISIBLE (-215 360);
FORCEPROP 1 LASTPIN (-225 350) BN 1
J 0
(-237 358);
DISPLAY 0.680851 (-237 358);
PAINT GREEN (-237 358);
FORCEPROP 2 LAST CDS_LIB standard
J 0
(-175 350);
DISPLAY INVISIBLE (-175 350);
FORCEPROP 1 LAST BODY_TYPE PLUMBING
J 0
(-175 400);
DISPLAY 0.872340 (-175 400);
PAINT GREEN (-175 400);
DISPLAY INVISIBLE (-175 400);
FORCEPROP 1 LAST HDL_TAP TRUE
J 0
(150 225);
DISPLAY 0.872340 (150 225);
DISPLAY INVISIBLE (150 225);
FORCEPROP 1 LAST PATH I277
J 0
(-177 350);
DISPLAY 0.872340 (-177 350);
PAINT GREEN (-177 350);
DISPLAY INVISIBLE (-177 350);
FORCEADD TAP..1
(-375 400);
FORCEPROP 3 LASTPIN (-425 400) SIG_NAME P5E_CPU0_PE4_TX_C_DN<1>
J 0
(-415 410);
DISPLAY 0.659574 (-415 410);
PAINT MONO (-415 410);
DISPLAY INVISIBLE (-415 410);
FORCEPROP 1 LASTPIN (-425 400) BN 1
J 0
(-437 408);
DISPLAY 0.680851 (-437 408);
PAINT GREEN (-437 408);
FORCEPROP 2 LAST CDS_LIB standard
J 0
(-375 400);
DISPLAY INVISIBLE (-375 400);
FORCEPROP 1 LAST BODY_TYPE PLUMBING
J 0
(-375 450);
DISPLAY 0.872340 (-375 450);
PAINT GREEN (-375 450);
DISPLAY INVISIBLE (-375 450);
FORCEPROP 1 LAST HDL_TAP TRUE
J 0
(-50 275);
DISPLAY 0.872340 (-50 275);
DISPLAY INVISIBLE (-50 275);
FORCEPROP 1 LAST PATH I278
J 0
(-377 400);
DISPLAY 0.872340 (-377 400);
PAINT GREEN (-377 400);
DISPLAY INVISIBLE (-377 400);
FORCEADD TAP..1
(-375 600);
FORCEPROP 3 LASTPIN (-425 600) SIG_NAME P5E_CPU0_PE4_TX_C_DN<2>
J 0
(-415 610);
DISPLAY 0.659574 (-415 610);
PAINT MONO (-415 610);
DISPLAY INVISIBLE (-415 610);
FORCEPROP 1 LASTPIN (-425 600) BN 2
J 0
(-437 608);
DISPLAY 0.680851 (-437 608);
PAINT GREEN (-437 608);
FORCEPROP 2 LAST CDS_LIB standard
J 0
(-375 600);
DISPLAY INVISIBLE (-375 600);
FORCEPROP 1 LAST BODY_TYPE PLUMBING
J 0
(-375 650);
DISPLAY 0.872340 (-375 650);
PAINT GREEN (-375 650);
DISPLAY INVISIBLE (-375 650);
FORCEPROP 1 LAST HDL_TAP TRUE
J 0
(-50 475);
DISPLAY 0.872340 (-50 475);
DISPLAY INVISIBLE (-50 475);
FORCEPROP 1 LAST PATH I279
J 0
(-377 600);
DISPLAY 0.872340 (-377 600);
PAINT GREEN (-377 600);
DISPLAY INVISIBLE (-377 600);
FORCEADD TAP..1
(-175 550);
FORCEPROP 3 LASTPIN (-225 550) SIG_NAME P5E_CPU0_PE4_TX_C_DP<2>
J 0
(-215 560);
DISPLAY 0.659574 (-215 560);
PAINT MONO (-215 560);
DISPLAY INVISIBLE (-215 560);
FORCEPROP 1 LASTPIN (-225 550) BN 2
J 0
(-237 558);
DISPLAY 0.680851 (-237 558);
PAINT GREEN (-237 558);
FORCEPROP 2 LAST CDS_LIB standard
J 0
(-175 550);
DISPLAY INVISIBLE (-175 550);
FORCEPROP 1 LAST BODY_TYPE PLUMBING
J 0
(-175 600);
DISPLAY 0.872340 (-175 600);
PAINT GREEN (-175 600);
DISPLAY INVISIBLE (-175 600);
FORCEPROP 1 LAST HDL_TAP TRUE
J 0
(150 425);
DISPLAY 0.872340 (150 425);
DISPLAY INVISIBLE (150 425);
FORCEPROP 1 LAST PATH I280
J 0
(-177 550);
DISPLAY 0.872340 (-177 550);
PAINT GREEN (-177 550);
DISPLAY INVISIBLE (-177 550);
FORCEADD TAP..1
(-175 750);
FORCEPROP 3 LASTPIN (-225 750) SIG_NAME P5E_CPU0_PE4_TX_C_DP<3>
J 0
(-215 760);
DISPLAY 0.659574 (-215 760);
PAINT MONO (-215 760);
DISPLAY INVISIBLE (-215 760);
FORCEPROP 1 LASTPIN (-225 750) BN 3
J 0
(-237 758);
DISPLAY 0.680851 (-237 758);
PAINT GREEN (-237 758);
FORCEPROP 2 LAST CDS_LIB standard
J 0
(-175 750);
DISPLAY INVISIBLE (-175 750);
FORCEPROP 1 LAST BODY_TYPE PLUMBING
J 0
(-175 800);
DISPLAY 0.872340 (-175 800);
PAINT GREEN (-175 800);
DISPLAY INVISIBLE (-175 800);
FORCEPROP 1 LAST HDL_TAP TRUE
J 0
(150 625);
DISPLAY 0.872340 (150 625);
DISPLAY INVISIBLE (150 625);
FORCEPROP 1 LAST PATH I281
J 0
(-177 750);
DISPLAY 0.872340 (-177 750);
PAINT GREEN (-177 750);
DISPLAY INVISIBLE (-177 750);
FORCEADD TAP..1
(-375 1000);
FORCEPROP 3 LASTPIN (-425 1000) SIG_NAME P5E_CPU0_PE4_TX_C_DN<4>
J 0
(-415 1010);
DISPLAY 0.659574 (-415 1010);
PAINT MONO (-415 1010);
DISPLAY INVISIBLE (-415 1010);
FORCEPROP 1 LASTPIN (-425 1000) BN 4
J 0
(-437 1008);
DISPLAY 0.680851 (-437 1008);
PAINT GREEN (-437 1008);
FORCEPROP 2 LAST CDS_LIB standard
J 0
(-375 1000);
DISPLAY INVISIBLE (-375 1000);
FORCEPROP 1 LAST BODY_TYPE PLUMBING
J 0
(-375 1050);
DISPLAY 0.872340 (-375 1050);
PAINT GREEN (-375 1050);
DISPLAY INVISIBLE (-375 1050);
FORCEPROP 1 LAST HDL_TAP TRUE
J 0
(-50 875);
DISPLAY 0.872340 (-50 875);
DISPLAY INVISIBLE (-50 875);
FORCEPROP 1 LAST PATH I282
J 0
(-377 1000);
DISPLAY 0.872340 (-377 1000);
PAINT GREEN (-377 1000);
DISPLAY INVISIBLE (-377 1000);
FORCEADD TAP..1
(-375 800);
FORCEPROP 3 LASTPIN (-425 800) SIG_NAME P5E_CPU0_PE4_TX_C_DN<3>
J 0
(-415 810);
DISPLAY 0.659574 (-415 810);
PAINT MONO (-415 810);
DISPLAY INVISIBLE (-415 810);
FORCEPROP 1 LASTPIN (-425 800) BN 3
J 0
(-437 808);
DISPLAY 0.680851 (-437 808);
PAINT GREEN (-437 808);
FORCEPROP 2 LAST CDS_LIB standard
J 0
(-375 800);
DISPLAY INVISIBLE (-375 800);
FORCEPROP 1 LAST BODY_TYPE PLUMBING
J 0
(-375 850);
DISPLAY 0.872340 (-375 850);
PAINT GREEN (-375 850);
DISPLAY INVISIBLE (-375 850);
FORCEPROP 1 LAST HDL_TAP TRUE
J 0
(-50 675);
DISPLAY 0.872340 (-50 675);
DISPLAY INVISIBLE (-50 675);
FORCEPROP 1 LAST PATH I283
J 0
(-377 800);
DISPLAY 0.872340 (-377 800);
PAINT GREEN (-377 800);
DISPLAY INVISIBLE (-377 800);
FORCEADD TAP..1
(-175 950);
FORCEPROP 3 LASTPIN (-225 950) SIG_NAME P5E_CPU0_PE4_TX_C_DP<4>
J 0
(-215 960);
DISPLAY 0.659574 (-215 960);
PAINT MONO (-215 960);
DISPLAY INVISIBLE (-215 960);
FORCEPROP 1 LASTPIN (-225 950) BN 4
J 0
(-237 958);
DISPLAY 0.680851 (-237 958);
PAINT GREEN (-237 958);
FORCEPROP 2 LAST CDS_LIB standard
J 0
(-175 950);
DISPLAY INVISIBLE (-175 950);
FORCEPROP 1 LAST BODY_TYPE PLUMBING
J 0
(-175 1000);
DISPLAY 0.872340 (-175 1000);
PAINT GREEN (-175 1000);
DISPLAY INVISIBLE (-175 1000);
FORCEPROP 1 LAST HDL_TAP TRUE
J 0
(150 825);
DISPLAY 0.872340 (150 825);
DISPLAY INVISIBLE (150 825);
FORCEPROP 1 LAST PATH I284
J 0
(-177 950);
DISPLAY 0.872340 (-177 950);
PAINT GREEN (-177 950);
DISPLAY INVISIBLE (-177 950);
FORCEADD TAP..1
(-375 1200);
FORCEPROP 3 LASTPIN (-425 1200) SIG_NAME P5E_CPU0_PE4_TX_C_DN<5>
J 0
(-415 1210);
DISPLAY 0.659574 (-415 1210);
PAINT MONO (-415 1210);
DISPLAY INVISIBLE (-415 1210);
FORCEPROP 1 LASTPIN (-425 1200) BN 5
J 0
(-437 1208);
DISPLAY 0.680851 (-437 1208);
PAINT GREEN (-437 1208);
FORCEPROP 2 LAST CDS_LIB standard
J 0
(-375 1200);
DISPLAY INVISIBLE (-375 1200);
FORCEPROP 1 LAST BODY_TYPE PLUMBING
J 0
(-375 1250);
DISPLAY 0.872340 (-375 1250);
PAINT GREEN (-375 1250);
DISPLAY INVISIBLE (-375 1250);
FORCEPROP 1 LAST HDL_TAP TRUE
J 0
(-50 1075);
DISPLAY 0.872340 (-50 1075);
DISPLAY INVISIBLE (-50 1075);
FORCEPROP 1 LAST PATH I285
J 0
(-377 1200);
DISPLAY 0.872340 (-377 1200);
PAINT GREEN (-377 1200);
DISPLAY INVISIBLE (-377 1200);
FORCEADD TAP..1
(-175 1150);
FORCEPROP 3 LASTPIN (-225 1150) SIG_NAME P5E_CPU0_PE4_TX_C_DP<5>
J 0
(-215 1160);
DISPLAY 0.659574 (-215 1160);
PAINT MONO (-215 1160);
DISPLAY INVISIBLE (-215 1160);
FORCEPROP 1 LASTPIN (-225 1150) BN 5
J 0
(-237 1158);
DISPLAY 0.680851 (-237 1158);
PAINT GREEN (-237 1158);
FORCEPROP 2 LAST CDS_LIB standard
J 0
(-175 1150);
DISPLAY INVISIBLE (-175 1150);
FORCEPROP 1 LAST BODY_TYPE PLUMBING
J 0
(-175 1200);
DISPLAY 0.872340 (-175 1200);
PAINT GREEN (-175 1200);
DISPLAY INVISIBLE (-175 1200);
FORCEPROP 1 LAST HDL_TAP TRUE
J 0
(150 1025);
DISPLAY 0.872340 (150 1025);
DISPLAY INVISIBLE (150 1025);
FORCEPROP 1 LAST PATH I286
J 0
(-177 1150);
DISPLAY 0.872340 (-177 1150);
PAINT GREEN (-177 1150);
DISPLAY INVISIBLE (-177 1150);
FORCEADD TAP..1
(-375 1400);
FORCEPROP 3 LASTPIN (-425 1400) SIG_NAME P5E_CPU0_PE4_TX_C_DN<6>
J 0
(-415 1410);
DISPLAY 0.659574 (-415 1410);
PAINT MONO (-415 1410);
DISPLAY INVISIBLE (-415 1410);
FORCEPROP 1 LASTPIN (-425 1400) BN 6
J 0
(-437 1408);
DISPLAY 0.680851 (-437 1408);
PAINT GREEN (-437 1408);
FORCEPROP 2 LAST CDS_LIB standard
J 0
(-375 1400);
DISPLAY INVISIBLE (-375 1400);
FORCEPROP 1 LAST BODY_TYPE PLUMBING
J 0
(-375 1450);
DISPLAY 0.872340 (-375 1450);
PAINT GREEN (-375 1450);
DISPLAY INVISIBLE (-375 1450);
FORCEPROP 1 LAST HDL_TAP TRUE
J 0
(-50 1275);
DISPLAY 0.872340 (-50 1275);
DISPLAY INVISIBLE (-50 1275);
FORCEPROP 1 LAST PATH I287
J 0
(-377 1400);
DISPLAY 0.872340 (-377 1400);
PAINT GREEN (-377 1400);
DISPLAY INVISIBLE (-377 1400);
FORCEADD TAP..1
(-175 1350);
FORCEPROP 3 LASTPIN (-225 1350) SIG_NAME P5E_CPU0_PE4_TX_C_DP<6>
J 0
(-215 1360);
DISPLAY 0.659574 (-215 1360);
PAINT MONO (-215 1360);
DISPLAY INVISIBLE (-215 1360);
FORCEPROP 1 LASTPIN (-225 1350) BN 6
J 0
(-237 1358);
DISPLAY 0.680851 (-237 1358);
PAINT GREEN (-237 1358);
FORCEPROP 2 LAST CDS_LIB standard
J 0
(-175 1350);
DISPLAY INVISIBLE (-175 1350);
FORCEPROP 1 LAST BODY_TYPE PLUMBING
J 0
(-175 1400);
DISPLAY 0.872340 (-175 1400);
PAINT GREEN (-175 1400);
DISPLAY INVISIBLE (-175 1400);
FORCEPROP 1 LAST HDL_TAP TRUE
J 0
(150 1225);
DISPLAY 0.872340 (150 1225);
DISPLAY INVISIBLE (150 1225);
FORCEPROP 1 LAST PATH I288
J 0
(-177 1350);
DISPLAY 0.872340 (-177 1350);
PAINT GREEN (-177 1350);
DISPLAY INVISIBLE (-177 1350);
FORCEADD TAP..1
(-375 1600);
FORCEPROP 3 LASTPIN (-425 1600) SIG_NAME P5E_CPU0_PE4_TX_C_DN<7>
J 0
(-415 1610);
DISPLAY 0.659574 (-415 1610);
PAINT MONO (-415 1610);
DISPLAY INVISIBLE (-415 1610);
FORCEPROP 1 LASTPIN (-425 1600) BN 7
J 0
(-437 1608);
DISPLAY 0.680851 (-437 1608);
PAINT GREEN (-437 1608);
FORCEPROP 2 LAST CDS_LIB standard
J 0
(-375 1600);
DISPLAY INVISIBLE (-375 1600);
FORCEPROP 1 LAST BODY_TYPE PLUMBING
J 0
(-375 1650);
DISPLAY 0.872340 (-375 1650);
PAINT GREEN (-375 1650);
DISPLAY INVISIBLE (-375 1650);
FORCEPROP 1 LAST HDL_TAP TRUE
J 0
(-50 1475);
DISPLAY 0.872340 (-50 1475);
DISPLAY INVISIBLE (-50 1475);
FORCEPROP 1 LAST PATH I289
J 0
(-377 1600);
DISPLAY 0.872340 (-377 1600);
PAINT GREEN (-377 1600);
DISPLAY INVISIBLE (-377 1600);
FORCEADD TAP..1
(-175 1550);
FORCEPROP 3 LASTPIN (-225 1550) SIG_NAME P5E_CPU0_PE4_TX_C_DP<7>
J 0
(-215 1560);
DISPLAY 0.659574 (-215 1560);
PAINT MONO (-215 1560);
DISPLAY INVISIBLE (-215 1560);
FORCEPROP 1 LASTPIN (-225 1550) BN 7
J 0
(-237 1558);
DISPLAY 0.680851 (-237 1558);
PAINT GREEN (-237 1558);
FORCEPROP 2 LAST CDS_LIB standard
J 0
(-175 1550);
DISPLAY INVISIBLE (-175 1550);
FORCEPROP 1 LAST BODY_TYPE PLUMBING
J 0
(-175 1600);
DISPLAY 0.872340 (-175 1600);
PAINT GREEN (-175 1600);
DISPLAY INVISIBLE (-175 1600);
FORCEPROP 1 LAST HDL_TAP TRUE
J 0
(150 1425);
DISPLAY 0.872340 (150 1425);
DISPLAY INVISIBLE (150 1425);
FORCEPROP 1 LAST PATH I290
J 0
(-177 1550);
DISPLAY 0.872340 (-177 1550);
PAINT GREEN (-177 1550);
DISPLAY INVISIBLE (-177 1550);
FORCEADD OFFPAGE..2
(825 1575);
FORCEPROP 2 LAST $XR0 139 
J 0
(1014 1575);
DISPLAY 0.638298 (1014 1575);
PAINT MONO (1014 1575);
FORCEPROP 2 LAST CDS_LIB standard
J 0
(825 1575);
DISPLAY INVISIBLE (825 1575);
FORCEPROP 1 LAST OFFPAGE TRUE
J 0
(1150 1450);
DISPLAY 0.872340 (1150 1450);
DISPLAY INVISIBLE (1150 1450);
FORCEPROP 1 LAST COMMENT_BODY TRUE
J 0
(780 1480);
DISPLAY 0.872340 (780 1480);
PAINT GREEN (780 1480);
DISPLAY INVISIBLE (780 1480);
FORCEPROP 2 LAST PATH I291
J 0
(1025 1625);
DISPLAY 1.021277 (1025 1625);
DISPLAY INVISIBLE (1025 1625);
FORCEADD OFFPAGE..2
(825 1625);
FORCEPROP 2 LAST $XR0 139 
J 0
(1014 1625);
DISPLAY 0.638298 (1014 1625);
PAINT MONO (1014 1625);
FORCEPROP 2 LAST CDS_LIB standard
J 0
(825 1625);
DISPLAY INVISIBLE (825 1625);
FORCEPROP 1 LAST OFFPAGE TRUE
J 0
(1150 1500);
DISPLAY 0.872340 (1150 1500);
DISPLAY INVISIBLE (1150 1500);
FORCEPROP 1 LAST COMMENT_BODY TRUE
J 0
(780 1530);
DISPLAY 0.872340 (780 1530);
PAINT GREEN (780 1530);
DISPLAY INVISIBLE (780 1530);
FORCEPROP 2 LAST PATH I292
J 0
(1025 1675);
DISPLAY 1.021277 (1025 1675);
DISPLAY INVISIBLE (1025 1675);
FORCEADD TAP..1
(-375 2175);
FORCEPROP 3 LASTPIN (-425 2175) SIG_NAME P5E_CPU0_PE4_TX_C_DN<8>
J 0
(-415 2185);
DISPLAY 0.659574 (-415 2185);
PAINT MONO (-415 2185);
DISPLAY INVISIBLE (-415 2185);
FORCEPROP 1 LASTPIN (-425 2175) BN 8
J 0
(-437 2183);
DISPLAY 0.680851 (-437 2183);
PAINT GREEN (-437 2183);
FORCEPROP 2 LAST CDS_LIB standard
J 0
(-375 2175);
DISPLAY INVISIBLE (-375 2175);
FORCEPROP 1 LAST BODY_TYPE PLUMBING
J 0
(-375 2225);
DISPLAY 0.872340 (-375 2225);
PAINT GREEN (-375 2225);
DISPLAY INVISIBLE (-375 2225);
FORCEPROP 1 LAST HDL_TAP TRUE
J 0
(-50 2050);
DISPLAY 0.872340 (-50 2050);
DISPLAY INVISIBLE (-50 2050);
FORCEPROP 1 LAST PATH I293
J 0
(-377 2175);
DISPLAY 0.872340 (-377 2175);
PAINT GREEN (-377 2175);
DISPLAY INVISIBLE (-377 2175);
FORCEADD TAP..1
(-175 2125);
FORCEPROP 3 LASTPIN (-225 2125) SIG_NAME P5E_CPU0_PE4_TX_C_DP<8>
J 0
(-215 2135);
DISPLAY 0.659574 (-215 2135);
PAINT MONO (-215 2135);
DISPLAY INVISIBLE (-215 2135);
FORCEPROP 1 LASTPIN (-225 2125) BN 8
J 0
(-237 2133);
DISPLAY 0.680851 (-237 2133);
PAINT GREEN (-237 2133);
FORCEPROP 2 LAST CDS_LIB standard
J 0
(-175 2125);
DISPLAY INVISIBLE (-175 2125);
FORCEPROP 1 LAST BODY_TYPE PLUMBING
J 0
(-175 2175);
DISPLAY 0.872340 (-175 2175);
PAINT GREEN (-175 2175);
DISPLAY INVISIBLE (-175 2175);
FORCEPROP 1 LAST HDL_TAP TRUE
J 0
(150 2000);
DISPLAY 0.872340 (150 2000);
DISPLAY INVISIBLE (150 2000);
FORCEPROP 1 LAST PATH I294
J 0
(-177 2125);
DISPLAY 0.872340 (-177 2125);
PAINT GREEN (-177 2125);
DISPLAY INVISIBLE (-177 2125);
FORCEADD TAP..1
(-375 2375);
FORCEPROP 3 LASTPIN (-425 2375) SIG_NAME P5E_CPU0_PE4_TX_C_DN<9>
J 0
(-415 2385);
DISPLAY 0.659574 (-415 2385);
PAINT MONO (-415 2385);
DISPLAY INVISIBLE (-415 2385);
FORCEPROP 1 LASTPIN (-425 2375) BN 9
J 0
(-437 2383);
DISPLAY 0.680851 (-437 2383);
PAINT GREEN (-437 2383);
FORCEPROP 2 LAST CDS_LIB standard
J 0
(-375 2375);
DISPLAY INVISIBLE (-375 2375);
FORCEPROP 1 LAST BODY_TYPE PLUMBING
J 0
(-375 2425);
DISPLAY 0.872340 (-375 2425);
PAINT GREEN (-375 2425);
DISPLAY INVISIBLE (-375 2425);
FORCEPROP 1 LAST HDL_TAP TRUE
J 0
(-50 2250);
DISPLAY 0.872340 (-50 2250);
DISPLAY INVISIBLE (-50 2250);
FORCEPROP 1 LAST PATH I295
J 0
(-377 2375);
DISPLAY 0.872340 (-377 2375);
PAINT GREEN (-377 2375);
DISPLAY INVISIBLE (-377 2375);
FORCEADD TAP..1
(-175 2325);
FORCEPROP 3 LASTPIN (-225 2325) SIG_NAME P5E_CPU0_PE4_TX_C_DP<9>
J 0
(-215 2335);
DISPLAY 0.659574 (-215 2335);
PAINT MONO (-215 2335);
DISPLAY INVISIBLE (-215 2335);
FORCEPROP 1 LASTPIN (-225 2325) BN 9
J 0
(-237 2333);
DISPLAY 0.680851 (-237 2333);
PAINT GREEN (-237 2333);
FORCEPROP 2 LAST CDS_LIB standard
J 0
(-175 2325);
DISPLAY INVISIBLE (-175 2325);
FORCEPROP 1 LAST BODY_TYPE PLUMBING
J 0
(-175 2375);
DISPLAY 0.872340 (-175 2375);
PAINT GREEN (-175 2375);
DISPLAY INVISIBLE (-175 2375);
FORCEPROP 1 LAST HDL_TAP TRUE
J 0
(150 2200);
DISPLAY 0.872340 (150 2200);
DISPLAY INVISIBLE (150 2200);
FORCEPROP 1 LAST PATH I296
J 0
(-177 2325);
DISPLAY 0.872340 (-177 2325);
PAINT GREEN (-177 2325);
DISPLAY INVISIBLE (-177 2325);
FORCEADD TAP..1
(-175 2525);
FORCEPROP 3 LASTPIN (-225 2525) SIG_NAME P5E_CPU0_PE4_TX_C_DP<10>
J 0
(-215 2535);
DISPLAY 0.659574 (-215 2535);
PAINT MONO (-215 2535);
DISPLAY INVISIBLE (-215 2535);
FORCEPROP 1 LASTPIN (-225 2525) BN 10
J 0
(-237 2533);
DISPLAY 0.680851 (-237 2533);
PAINT GREEN (-237 2533);
FORCEPROP 2 LAST CDS_LIB standard
J 0
(-175 2525);
DISPLAY INVISIBLE (-175 2525);
FORCEPROP 1 LAST BODY_TYPE PLUMBING
J 0
(-175 2575);
DISPLAY 0.872340 (-175 2575);
PAINT GREEN (-175 2575);
DISPLAY INVISIBLE (-175 2575);
FORCEPROP 1 LAST HDL_TAP TRUE
J 0
(150 2400);
DISPLAY 0.872340 (150 2400);
DISPLAY INVISIBLE (150 2400);
FORCEPROP 1 LAST PATH I297
J 0
(-177 2525);
DISPLAY 0.872340 (-177 2525);
PAINT GREEN (-177 2525);
DISPLAY INVISIBLE (-177 2525);
FORCEADD TAP..1
(-375 2775);
FORCEPROP 3 LASTPIN (-425 2775) SIG_NAME P5E_CPU0_PE4_TX_C_DN<11>
J 0
(-415 2785);
DISPLAY 0.659574 (-415 2785);
PAINT MONO (-415 2785);
DISPLAY INVISIBLE (-415 2785);
FORCEPROP 1 LASTPIN (-425 2775) BN 11
J 0
(-437 2783);
DISPLAY 0.680851 (-437 2783);
PAINT GREEN (-437 2783);
FORCEPROP 2 LAST CDS_LIB standard
J 0
(-375 2775);
DISPLAY INVISIBLE (-375 2775);
FORCEPROP 1 LAST BODY_TYPE PLUMBING
J 0
(-375 2825);
DISPLAY 0.872340 (-375 2825);
PAINT GREEN (-375 2825);
DISPLAY INVISIBLE (-375 2825);
FORCEPROP 1 LAST HDL_TAP TRUE
J 0
(-50 2650);
DISPLAY 0.872340 (-50 2650);
DISPLAY INVISIBLE (-50 2650);
FORCEPROP 1 LAST PATH I298
J 0
(-377 2775);
DISPLAY 0.872340 (-377 2775);
PAINT GREEN (-377 2775);
DISPLAY INVISIBLE (-377 2775);
FORCEADD TAP..1
(-375 2575);
FORCEPROP 3 LASTPIN (-425 2575) SIG_NAME P5E_CPU0_PE4_TX_C_DN<10>
J 0
(-415 2585);
DISPLAY 0.659574 (-415 2585);
PAINT MONO (-415 2585);
DISPLAY INVISIBLE (-415 2585);
FORCEPROP 1 LASTPIN (-425 2575) BN 10
J 0
(-437 2583);
DISPLAY 0.680851 (-437 2583);
PAINT GREEN (-437 2583);
FORCEPROP 2 LAST CDS_LIB standard
J 0
(-375 2575);
DISPLAY INVISIBLE (-375 2575);
FORCEPROP 1 LAST BODY_TYPE PLUMBING
J 0
(-375 2625);
DISPLAY 0.872340 (-375 2625);
PAINT GREEN (-375 2625);
DISPLAY INVISIBLE (-375 2625);
FORCEPROP 1 LAST HDL_TAP TRUE
J 0
(-50 2450);
DISPLAY 0.872340 (-50 2450);
DISPLAY INVISIBLE (-50 2450);
FORCEPROP 1 LAST PATH I299
J 0
(-377 2575);
DISPLAY 0.872340 (-377 2575);
PAINT GREEN (-377 2575);
DISPLAY INVISIBLE (-377 2575);
FORCEADD TAP..1
(-175 2725);
FORCEPROP 3 LASTPIN (-225 2725) SIG_NAME P5E_CPU0_PE4_TX_C_DP<11>
J 0
(-215 2735);
DISPLAY 0.659574 (-215 2735);
PAINT MONO (-215 2735);
DISPLAY INVISIBLE (-215 2735);
FORCEPROP 1 LASTPIN (-225 2725) BN 11
J 0
(-237 2733);
DISPLAY 0.680851 (-237 2733);
PAINT GREEN (-237 2733);
FORCEPROP 2 LAST CDS_LIB standard
J 0
(-175 2725);
DISPLAY INVISIBLE (-175 2725);
FORCEPROP 1 LAST BODY_TYPE PLUMBING
J 0
(-175 2775);
DISPLAY 0.872340 (-175 2775);
PAINT GREEN (-175 2775);
DISPLAY INVISIBLE (-175 2775);
FORCEPROP 1 LAST HDL_TAP TRUE
J 0
(150 2600);
DISPLAY 0.872340 (150 2600);
DISPLAY INVISIBLE (150 2600);
FORCEPROP 1 LAST PATH I300
J 0
(-177 2725);
DISPLAY 0.872340 (-177 2725);
PAINT GREEN (-177 2725);
DISPLAY INVISIBLE (-177 2725);
FORCEADD TAP..1
(-375 2975);
FORCEPROP 3 LASTPIN (-425 2975) SIG_NAME P5E_CPU0_PE4_TX_C_DN<12>
J 0
(-415 2985);
DISPLAY 0.659574 (-415 2985);
PAINT MONO (-415 2985);
DISPLAY INVISIBLE (-415 2985);
FORCEPROP 1 LASTPIN (-425 2975) BN 12
J 0
(-437 2983);
DISPLAY 0.680851 (-437 2983);
PAINT GREEN (-437 2983);
FORCEPROP 2 LAST CDS_LIB standard
J 0
(-375 2975);
DISPLAY INVISIBLE (-375 2975);
FORCEPROP 1 LAST BODY_TYPE PLUMBING
J 0
(-375 3025);
DISPLAY 0.872340 (-375 3025);
PAINT GREEN (-375 3025);
DISPLAY INVISIBLE (-375 3025);
FORCEPROP 1 LAST HDL_TAP TRUE
J 0
(-50 2850);
DISPLAY 0.872340 (-50 2850);
DISPLAY INVISIBLE (-50 2850);
FORCEPROP 1 LAST PATH I301
J 0
(-377 2975);
DISPLAY 0.872340 (-377 2975);
PAINT GREEN (-377 2975);
DISPLAY INVISIBLE (-377 2975);
FORCEADD TAP..1
(-175 2925);
FORCEPROP 3 LASTPIN (-225 2925) SIG_NAME P5E_CPU0_PE4_TX_C_DP<12>
J 0
(-215 2935);
DISPLAY 0.659574 (-215 2935);
PAINT MONO (-215 2935);
DISPLAY INVISIBLE (-215 2935);
FORCEPROP 1 LASTPIN (-225 2925) BN 12
J 0
(-237 2933);
DISPLAY 0.680851 (-237 2933);
PAINT GREEN (-237 2933);
FORCEPROP 2 LAST CDS_LIB standard
J 0
(-175 2925);
DISPLAY INVISIBLE (-175 2925);
FORCEPROP 1 LAST BODY_TYPE PLUMBING
J 0
(-175 2975);
DISPLAY 0.872340 (-175 2975);
PAINT GREEN (-175 2975);
DISPLAY INVISIBLE (-175 2975);
FORCEPROP 1 LAST HDL_TAP TRUE
J 0
(150 2800);
DISPLAY 0.872340 (150 2800);
DISPLAY INVISIBLE (150 2800);
FORCEPROP 1 LAST PATH I302
J 0
(-177 2925);
DISPLAY 0.872340 (-177 2925);
PAINT GREEN (-177 2925);
DISPLAY INVISIBLE (-177 2925);
FORCEADD TAP..1
(-375 3175);
FORCEPROP 3 LASTPIN (-425 3175) SIG_NAME P5E_CPU0_PE4_TX_C_DN<13>
J 0
(-415 3185);
DISPLAY 0.659574 (-415 3185);
PAINT MONO (-415 3185);
DISPLAY INVISIBLE (-415 3185);
FORCEPROP 1 LASTPIN (-425 3175) BN 13
J 0
(-437 3183);
DISPLAY 0.680851 (-437 3183);
PAINT GREEN (-437 3183);
FORCEPROP 2 LAST CDS_LIB standard
J 0
(-375 3175);
DISPLAY INVISIBLE (-375 3175);
FORCEPROP 1 LAST BODY_TYPE PLUMBING
J 0
(-375 3225);
DISPLAY 0.872340 (-375 3225);
PAINT GREEN (-375 3225);
DISPLAY INVISIBLE (-375 3225);
FORCEPROP 1 LAST HDL_TAP TRUE
J 0
(-50 3050);
DISPLAY 0.872340 (-50 3050);
DISPLAY INVISIBLE (-50 3050);
FORCEPROP 1 LAST PATH I303
J 0
(-377 3175);
DISPLAY 0.872340 (-377 3175);
PAINT GREEN (-377 3175);
DISPLAY INVISIBLE (-377 3175);
FORCEADD TAP..1
(-175 3325);
FORCEPROP 3 LASTPIN (-225 3325) SIG_NAME P5E_CPU0_PE4_TX_C_DP<14>
J 0
(-215 3335);
DISPLAY 0.659574 (-215 3335);
PAINT MONO (-215 3335);
DISPLAY INVISIBLE (-215 3335);
FORCEPROP 1 LASTPIN (-225 3325) BN 14
J 0
(-237 3333);
DISPLAY 0.680851 (-237 3333);
PAINT GREEN (-237 3333);
FORCEPROP 2 LAST CDS_LIB standard
J 0
(-175 3325);
DISPLAY INVISIBLE (-175 3325);
FORCEPROP 1 LAST BODY_TYPE PLUMBING
J 0
(-175 3375);
DISPLAY 0.872340 (-175 3375);
PAINT GREEN (-175 3375);
DISPLAY INVISIBLE (-175 3375);
FORCEPROP 1 LAST HDL_TAP TRUE
J 0
(150 3200);
DISPLAY 0.872340 (150 3200);
DISPLAY INVISIBLE (150 3200);
FORCEPROP 1 LAST PATH I304
J 0
(-177 3325);
DISPLAY 0.872340 (-177 3325);
PAINT GREEN (-177 3325);
DISPLAY INVISIBLE (-177 3325);
FORCEADD TAP..1
(-175 3125);
FORCEPROP 3 LASTPIN (-225 3125) SIG_NAME P5E_CPU0_PE4_TX_C_DP<13>
J 0
(-215 3135);
DISPLAY 0.659574 (-215 3135);
PAINT MONO (-215 3135);
DISPLAY INVISIBLE (-215 3135);
FORCEPROP 1 LASTPIN (-225 3125) BN 13
J 0
(-237 3133);
DISPLAY 0.680851 (-237 3133);
PAINT GREEN (-237 3133);
FORCEPROP 2 LAST CDS_LIB standard
J 0
(-175 3125);
DISPLAY INVISIBLE (-175 3125);
FORCEPROP 1 LAST BODY_TYPE PLUMBING
J 0
(-175 3175);
DISPLAY 0.872340 (-175 3175);
PAINT GREEN (-175 3175);
DISPLAY INVISIBLE (-175 3175);
FORCEPROP 1 LAST HDL_TAP TRUE
J 0
(150 3000);
DISPLAY 0.872340 (150 3000);
DISPLAY INVISIBLE (150 3000);
FORCEPROP 1 LAST PATH I305
J 0
(-177 3125);
DISPLAY 0.872340 (-177 3125);
PAINT GREEN (-177 3125);
DISPLAY INVISIBLE (-177 3125);
FORCEADD TAP..1
(-375 3375);
FORCEPROP 3 LASTPIN (-425 3375) SIG_NAME P5E_CPU0_PE4_TX_C_DN<14>
J 0
(-415 3385);
DISPLAY 0.659574 (-415 3385);
PAINT MONO (-415 3385);
DISPLAY INVISIBLE (-415 3385);
FORCEPROP 1 LASTPIN (-425 3375) BN 14
J 0
(-437 3383);
DISPLAY 0.680851 (-437 3383);
PAINT GREEN (-437 3383);
FORCEPROP 2 LAST CDS_LIB standard
J 0
(-375 3375);
DISPLAY INVISIBLE (-375 3375);
FORCEPROP 1 LAST BODY_TYPE PLUMBING
J 0
(-375 3425);
DISPLAY 0.872340 (-375 3425);
PAINT GREEN (-375 3425);
DISPLAY INVISIBLE (-375 3425);
FORCEPROP 1 LAST HDL_TAP TRUE
J 0
(-50 3250);
DISPLAY 0.872340 (-50 3250);
DISPLAY INVISIBLE (-50 3250);
FORCEPROP 1 LAST PATH I306
J 0
(-377 3375);
DISPLAY 0.872340 (-377 3375);
PAINT GREEN (-377 3375);
DISPLAY INVISIBLE (-377 3375);
FORCEADD TAP..1
(-375 3575);
FORCEPROP 3 LASTPIN (-425 3575) SIG_NAME P5E_CPU0_PE4_TX_C_DN<15>
J 0
(-415 3585);
DISPLAY 0.659574 (-415 3585);
PAINT MONO (-415 3585);
DISPLAY INVISIBLE (-415 3585);
FORCEPROP 1 LASTPIN (-425 3575) BN 15
J 0
(-437 3583);
DISPLAY 0.680851 (-437 3583);
PAINT GREEN (-437 3583);
FORCEPROP 2 LAST CDS_LIB standard
J 0
(-375 3575);
DISPLAY INVISIBLE (-375 3575);
FORCEPROP 1 LAST BODY_TYPE PLUMBING
J 0
(-375 3625);
DISPLAY 0.872340 (-375 3625);
PAINT GREEN (-375 3625);
DISPLAY INVISIBLE (-375 3625);
FORCEPROP 1 LAST HDL_TAP TRUE
J 0
(-50 3450);
DISPLAY 0.872340 (-50 3450);
DISPLAY INVISIBLE (-50 3450);
FORCEPROP 1 LAST PATH I307
J 0
(-377 3575);
DISPLAY 0.872340 (-377 3575);
PAINT GREEN (-377 3575);
DISPLAY INVISIBLE (-377 3575);
FORCEADD TAP..1
(-175 3525);
FORCEPROP 3 LASTPIN (-225 3525) SIG_NAME P5E_CPU0_PE4_TX_C_DP<15>
J 0
(-215 3535);
DISPLAY 0.659574 (-215 3535);
PAINT MONO (-215 3535);
DISPLAY INVISIBLE (-215 3535);
FORCEPROP 1 LASTPIN (-225 3525) BN 15
J 0
(-237 3533);
DISPLAY 0.680851 (-237 3533);
PAINT GREEN (-237 3533);
FORCEPROP 2 LAST CDS_LIB standard
J 0
(-175 3525);
DISPLAY INVISIBLE (-175 3525);
FORCEPROP 1 LAST BODY_TYPE PLUMBING
J 0
(-175 3575);
DISPLAY 0.872340 (-175 3575);
PAINT GREEN (-175 3575);
DISPLAY INVISIBLE (-175 3575);
FORCEPROP 1 LAST HDL_TAP TRUE
J 0
(150 3400);
DISPLAY 0.872340 (150 3400);
DISPLAY INVISIBLE (150 3400);
FORCEPROP 1 LAST PATH I308
J 0
(-177 3525);
DISPLAY 0.872340 (-177 3525);
PAINT GREEN (-177 3525);
DISPLAY INVISIBLE (-177 3525);
FORCEADD OFFPAGE..2
(825 3550);
FORCEPROP 2 LAST $XR0 138 
J 0
(1014 3550);
DISPLAY 0.638298 (1014 3550);
PAINT MONO (1014 3550);
FORCEPROP 2 LAST CDS_LIB standard
J 0
(825 3550);
DISPLAY INVISIBLE (825 3550);
FORCEPROP 1 LAST OFFPAGE TRUE
J 0
(1150 3425);
DISPLAY 0.872340 (1150 3425);
DISPLAY INVISIBLE (1150 3425);
FORCEPROP 1 LAST COMMENT_BODY TRUE
J 0
(780 3455);
DISPLAY 0.872340 (780 3455);
PAINT GREEN (780 3455);
DISPLAY INVISIBLE (780 3455);
FORCEPROP 2 LAST PATH I309
J 0
(1025 3600);
DISPLAY 1.021277 (1025 3600);
DISPLAY INVISIBLE (1025 3600);
FORCEADD OFFPAGE..2
(825 3600);
FORCEPROP 2 LAST $XR0 138 
J 0
(1014 3600);
DISPLAY 0.638298 (1014 3600);
PAINT MONO (1014 3600);
FORCEPROP 2 LAST CDS_LIB standard
J 0
(825 3600);
DISPLAY INVISIBLE (825 3600);
FORCEPROP 1 LAST OFFPAGE TRUE
J 0
(1150 3475);
DISPLAY 0.872340 (1150 3475);
DISPLAY INVISIBLE (1150 3475);
FORCEPROP 1 LAST COMMENT_BODY TRUE
J 0
(780 3505);
DISPLAY 0.872340 (780 3505);
PAINT GREEN (780 3505);
DISPLAY INVISIBLE (780 3505);
FORCEPROP 2 LAST PATH I310
J 0
(1025 3650);
DISPLAY 1.021277 (1025 3650);
DISPLAY INVISIBLE (1025 3650);
FORCEADD Q_CAP_DIFFBUS..2
R 2
(-925 350);
FORCEPROP 1 LAST PART_NUMBER SP_CH4221MEE01
J 2
(-1041 438);
DISPLAY 0.574468 (-1041 438);
PAINT GREEN (-1041 438);
DISPLAY INVISIBLE (-1041 438);
FORCEPROP 2 LAST VALUE DIFF BUS_0.22UF
J 2
(-1075 350);
DISPLAY 0.553191 (-1075 350);
FORCEPROP 1 LAST $LOCATION C1577
J 2
(-675 375);
DISPLAY 0.723404 (-675 375);
PAINT GREEN (-675 375);
FORCEPROP 2 LASTPIN (-850 350) $PN 1
J 0
(-840 360);
DISPLAY 0.808511 (-840 360);
FORCEPROP 2 LASTPIN (-1000 350) $PN 2
J 2
(-1010 360);
DISPLAY 0.808511 (-1010 360);
FORCEPROP 1 LAST PIN_NAMES_ROTATE TRUE
J 2
(-925 350);
DISPLAY 0.489362 (-925 350);
PAINT GREEN (-925 350);
DISPLAY INVISIBLE (-925 350);
FORCEPROP 2 LAST CDS_LIB pure_quanta
J 2
(-925 350);
DISPLAY INVISIBLE (-925 350);
FORCEPROP 1 LAST CDS_LMAN_SYM_OUTLINE -25,50,25,-50
J 2
(-925 350);
DISPLAY 0.468085 (-925 350);
PAINT GREEN (-925 350);
DISPLAY INVISIBLE (-925 350);
FORCEPROP 2 LAST VOLTAGE 6.3V
J 2
(-1275 400);
DISPLAY 0.553191 (-1275 400);
DISPLAY INVISIBLE (-1275 400);
FORCEPROP 1 LAST MATERIAL X6S
J 2
(-916 429);
DISPLAY 0.574468 (-916 429);
PAINT GREEN (-916 429);
DISPLAY INVISIBLE (-916 429);
FORCEPROP 2 LAST PACK_TYPE C0201
J 2
(-1100 400);
DISPLAY 0.553191 (-1100 400);
DISPLAY INVISIBLE (-1100 400);
FORCEPROP 2 LAST TOLERANCE 20%
J 2
(-1000 400);
DISPLAY 0.553191 (-1000 400);
DISPLAY INVISIBLE (-1000 400);
FORCEPROP 1 LAST PATH I311
J 2
(-925 350);
DISPLAY 0.723404 (-925 350);
DISPLAY INVISIBLE (-925 350);
FORCEPROP 0 LAST CDS_LOCATION C1577
J 0
(-675 425);
DISPLAY 1.021277 (-675 425);
DISPLAY INVISIBLE (-675 425);
FORCEPROP 2 LAST $SEC 1
J 2
(-750 425);
DISPLAY 0.680851 (-750 425);
PAINT MONO (-750 425);
DISPLAY INVISIBLE (-750 425);
FORCEPROP 2 LAST CDS_SEC 1
J 2
(-750 425);
DISPLAY 0.680851 (-750 425);
DISPLAY INVISIBLE (-750 425);
FORCEADD Q_CAP_DIFFBUS..2
R 2
(-925 400);
FORCEPROP 1 LAST PART_NUMBER SP_CH4221MEE01
J 2
(-1041 488);
DISPLAY 0.574468 (-1041 488);
PAINT GREEN (-1041 488);
DISPLAY INVISIBLE (-1041 488);
FORCEPROP 2 LAST VALUE DIFF BUS_0.22UF
J 2
(-1075 400);
DISPLAY 0.553191 (-1075 400);
FORCEPROP 1 LAST $LOCATION C1576
J 2
(-675 425);
DISPLAY 0.723404 (-675 425);
PAINT GREEN (-675 425);
FORCEPROP 2 LASTPIN (-850 400) $PN 1
J 0
(-840 410);
DISPLAY 0.808511 (-840 410);
FORCEPROP 2 LASTPIN (-1000 400) $PN 2
J 2
(-1010 410);
DISPLAY 0.808511 (-1010 410);
FORCEPROP 1 LAST PIN_NAMES_ROTATE TRUE
J 2
(-925 400);
DISPLAY 0.489362 (-925 400);
PAINT GREEN (-925 400);
DISPLAY INVISIBLE (-925 400);
FORCEPROP 1 LAST CDS_LMAN_SYM_OUTLINE -25,50,25,-50
J 2
(-925 400);
DISPLAY 0.468085 (-925 400);
PAINT GREEN (-925 400);
DISPLAY INVISIBLE (-925 400);
FORCEPROP 2 LAST CDS_LIB pure_quanta
J 2
(-925 400);
DISPLAY INVISIBLE (-925 400);
FORCEPROP 2 LAST VOLTAGE 6.3V
J 2
(-1275 450);
DISPLAY 0.553191 (-1275 450);
DISPLAY INVISIBLE (-1275 450);
FORCEPROP 1 LAST MATERIAL X6S
J 2
(-916 479);
DISPLAY 0.574468 (-916 479);
PAINT GREEN (-916 479);
DISPLAY INVISIBLE (-916 479);
FORCEPROP 2 LAST PACK_TYPE C0201
J 2
(-1100 450);
DISPLAY 0.553191 (-1100 450);
DISPLAY INVISIBLE (-1100 450);
FORCEPROP 2 LAST TOLERANCE 20%
J 2
(-1000 450);
DISPLAY 0.553191 (-1000 450);
DISPLAY INVISIBLE (-1000 450);
FORCEPROP 1 LAST PATH I312
J 2
(-925 400);
DISPLAY 0.723404 (-925 400);
DISPLAY INVISIBLE (-925 400);
FORCEPROP 0 LAST CDS_LOCATION C1576
J 0
(-675 475);
DISPLAY 1.021277 (-675 475);
DISPLAY INVISIBLE (-675 475);
FORCEPROP 2 LAST $SEC 1
J 2
(-750 475);
DISPLAY 0.680851 (-750 475);
PAINT MONO (-750 475);
DISPLAY INVISIBLE (-750 475);
FORCEPROP 2 LAST CDS_SEC 1
J 2
(-750 475);
DISPLAY 0.680851 (-750 475);
DISPLAY INVISIBLE (-750 475);
FORCEADD OFFPAGE..1
(1650 1625);
FORCEPROP 2 LAST $XR0 60 
J 0
(1429 1625);
DISPLAY 0.638298 (1429 1625);
PAINT MONO (1429 1625);
FORCEPROP 2 LAST CDS_LIB standard
J 0
(1650 1625);
DISPLAY INVISIBLE (1650 1625);
FORCEPROP 1 LAST OFFPAGE TRUE
J 0
(1975 1500);
DISPLAY 0.872340 (1975 1500);
DISPLAY INVISIBLE (1975 1500);
FORCEPROP 1 LAST COMMENT_BODY TRUE
J 0
(1775 1525);
DISPLAY 0.872340 (1775 1525);
PAINT GREEN (1775 1525);
DISPLAY INVISIBLE (1775 1525);
FORCEPROP 2 LAST PATH I313
J 0
(1375 1675);
DISPLAY 1.021277 (1375 1675);
DISPLAY INVISIBLE (1375 1675);
FORCEADD OFFPAGE..1
(1650 1575);
FORCEPROP 2 LAST $XR0 60 
J 0
(1429 1575);
DISPLAY 0.638298 (1429 1575);
PAINT MONO (1429 1575);
FORCEPROP 2 LAST CDS_LIB standard
J 0
(1650 1575);
DISPLAY INVISIBLE (1650 1575);
FORCEPROP 1 LAST OFFPAGE TRUE
J 0
(1975 1450);
DISPLAY 0.872340 (1975 1450);
DISPLAY INVISIBLE (1975 1450);
FORCEPROP 1 LAST COMMENT_BODY TRUE
J 0
(1775 1475);
DISPLAY 0.872340 (1775 1475);
PAINT GREEN (1775 1475);
DISPLAY INVISIBLE (1775 1475);
FORCEPROP 2 LAST PATH I314
J 0
(1375 1625);
DISPLAY 1.021277 (1375 1625);
DISPLAY INVISIBLE (1375 1625);
FORCEADD OFFPAGE..1
(1650 3550);
FORCEPROP 2 LAST $XR0 60 
J 0
(1429 3550);
DISPLAY 0.638298 (1429 3550);
PAINT MONO (1429 3550);
FORCEPROP 2 LAST CDS_LIB standard
J 0
(1650 3550);
DISPLAY INVISIBLE (1650 3550);
FORCEPROP 1 LAST OFFPAGE TRUE
J 0
(1975 3425);
DISPLAY 0.872340 (1975 3425);
DISPLAY INVISIBLE (1975 3425);
FORCEPROP 1 LAST COMMENT_BODY TRUE
J 0
(1775 3450);
DISPLAY 0.872340 (1775 3450);
PAINT GREEN (1775 3450);
DISPLAY INVISIBLE (1775 3450);
FORCEPROP 2 LAST PATH I315
J 0
(1375 3600);
DISPLAY 1.021277 (1375 3600);
DISPLAY INVISIBLE (1375 3600);
FORCEADD OFFPAGE..1
(1650 3600);
FORCEPROP 2 LAST $XR0 60 
J 0
(1429 3600);
DISPLAY 0.638298 (1429 3600);
PAINT MONO (1429 3600);
FORCEPROP 2 LAST CDS_LIB standard
J 0
(1650 3600);
DISPLAY INVISIBLE (1650 3600);
FORCEPROP 1 LAST OFFPAGE TRUE
J 0
(1975 3475);
DISPLAY 0.872340 (1975 3475);
DISPLAY INVISIBLE (1975 3475);
FORCEPROP 1 LAST COMMENT_BODY TRUE
J 0
(1775 3500);
DISPLAY 0.872340 (1775 3500);
PAINT GREEN (1775 3500);
DISPLAY INVISIBLE (1775 3500);
FORCEPROP 2 LAST PATH I316
J 0
(1375 3650);
DISPLAY 1.021277 (1375 3650);
DISPLAY INVISIBLE (1375 3650);
FORCEADD TAP..1
R 2
(2600 150);
FORCEPROP 3 LASTPIN (2650 150) SIG_NAME P5E_CPU1_PE1_TX_DP<0>
J 0
(2660 160);
DISPLAY 0.659574 (2660 160);
PAINT MONO (2660 160);
DISPLAY INVISIBLE (2660 160);
FORCEPROP 1 LASTPIN (2650 150) BN 0
J 2
(2662 158);
DISPLAY 0.680851 (2662 158);
PAINT GREEN (2662 158);
FORCEPROP 2 LAST CDS_LIB standard
J 0
(2600 150);
DISPLAY INVISIBLE (2600 150);
FORCEPROP 1 LAST BODY_TYPE PLUMBING
J 2
(2600 200);
DISPLAY 0.872340 (2600 200);
PAINT GREEN (2600 200);
DISPLAY INVISIBLE (2600 200);
FORCEPROP 1 LAST HDL_TAP TRUE
J 2
(2275 25);
DISPLAY 0.872340 (2275 25);
DISPLAY INVISIBLE (2275 25);
FORCEPROP 1 LAST PATH I317
J 2
(2602 150);
DISPLAY 0.872340 (2602 150);
PAINT GREEN (2602 150);
DISPLAY INVISIBLE (2602 150);
FORCEADD TAP..1
R 2
(2600 350);
FORCEPROP 3 LASTPIN (2650 350) SIG_NAME P5E_CPU1_PE1_TX_DP<1>
J 0
(2660 360);
DISPLAY 0.659574 (2660 360);
PAINT MONO (2660 360);
DISPLAY INVISIBLE (2660 360);
FORCEPROP 1 LASTPIN (2650 350) BN 1
J 2
(2662 358);
DISPLAY 0.680851 (2662 358);
PAINT GREEN (2662 358);
FORCEPROP 2 LAST CDS_LIB standard
J 0
(2600 350);
DISPLAY INVISIBLE (2600 350);
FORCEPROP 1 LAST BODY_TYPE PLUMBING
J 2
(2600 400);
DISPLAY 0.872340 (2600 400);
PAINT GREEN (2600 400);
DISPLAY INVISIBLE (2600 400);
FORCEPROP 1 LAST HDL_TAP TRUE
J 2
(2275 225);
DISPLAY 0.872340 (2275 225);
DISPLAY INVISIBLE (2275 225);
FORCEPROP 1 LAST PATH I318
J 2
(2602 350);
DISPLAY 0.872340 (2602 350);
PAINT GREEN (2602 350);
DISPLAY INVISIBLE (2602 350);
FORCEADD TAP..1
R 2
(2850 200);
FORCEPROP 3 LASTPIN (2900 200) SIG_NAME P5E_CPU1_PE1_TX_DN<0>
J 0
(2910 210);
DISPLAY 0.659574 (2910 210);
PAINT MONO (2910 210);
DISPLAY INVISIBLE (2910 210);
FORCEPROP 1 LASTPIN (2900 200) BN 0
J 2
(2912 208);
DISPLAY 0.680851 (2912 208);
PAINT GREEN (2912 208);
FORCEPROP 2 LAST CDS_LIB standard
J 0
(2850 200);
DISPLAY INVISIBLE (2850 200);
FORCEPROP 1 LAST BODY_TYPE PLUMBING
J 2
(2850 250);
DISPLAY 0.872340 (2850 250);
PAINT GREEN (2850 250);
DISPLAY INVISIBLE (2850 250);
FORCEPROP 1 LAST HDL_TAP TRUE
J 2
(2525 75);
DISPLAY 0.872340 (2525 75);
DISPLAY INVISIBLE (2525 75);
FORCEPROP 1 LAST PATH I319
J 2
(2852 200);
DISPLAY 0.872340 (2852 200);
PAINT GREEN (2852 200);
DISPLAY INVISIBLE (2852 200);
FORCEADD TAP..1
R 2
(2850 400);
FORCEPROP 3 LASTPIN (2900 400) SIG_NAME P5E_CPU1_PE1_TX_DN<1>
J 0
(2910 410);
DISPLAY 0.659574 (2910 410);
PAINT MONO (2910 410);
DISPLAY INVISIBLE (2910 410);
FORCEPROP 1 LASTPIN (2900 400) BN 1
J 2
(2912 408);
DISPLAY 0.680851 (2912 408);
PAINT GREEN (2912 408);
FORCEPROP 2 LAST CDS_LIB standard
J 0
(2850 400);
DISPLAY INVISIBLE (2850 400);
FORCEPROP 1 LAST BODY_TYPE PLUMBING
J 2
(2850 450);
DISPLAY 0.872340 (2850 450);
PAINT GREEN (2850 450);
DISPLAY INVISIBLE (2850 450);
FORCEPROP 1 LAST HDL_TAP TRUE
J 2
(2525 275);
DISPLAY 0.872340 (2525 275);
DISPLAY INVISIBLE (2525 275);
FORCEPROP 1 LAST PATH I320
J 2
(2852 400);
DISPLAY 0.872340 (2852 400);
PAINT GREEN (2852 400);
DISPLAY INVISIBLE (2852 400);
FORCEADD TAP..1
R 2
(2600 550);
FORCEPROP 3 LASTPIN (2650 550) SIG_NAME P5E_CPU1_PE1_TX_DP<2>
J 0
(2660 560);
DISPLAY 0.659574 (2660 560);
PAINT MONO (2660 560);
DISPLAY INVISIBLE (2660 560);
FORCEPROP 1 LASTPIN (2650 550) BN 2
J 2
(2662 558);
DISPLAY 0.680851 (2662 558);
PAINT GREEN (2662 558);
FORCEPROP 2 LAST CDS_LIB standard
J 0
(2600 550);
DISPLAY INVISIBLE (2600 550);
FORCEPROP 1 LAST BODY_TYPE PLUMBING
J 2
(2600 600);
DISPLAY 0.872340 (2600 600);
PAINT GREEN (2600 600);
DISPLAY INVISIBLE (2600 600);
FORCEPROP 1 LAST HDL_TAP TRUE
J 2
(2275 425);
DISPLAY 0.872340 (2275 425);
DISPLAY INVISIBLE (2275 425);
FORCEPROP 1 LAST PATH I321
J 2
(2602 550);
DISPLAY 0.872340 (2602 550);
PAINT GREEN (2602 550);
DISPLAY INVISIBLE (2602 550);
FORCEADD TAP..1
R 2
(2600 750);
FORCEPROP 3 LASTPIN (2650 750) SIG_NAME P5E_CPU1_PE1_TX_DP<3>
J 0
(2660 760);
DISPLAY 0.659574 (2660 760);
PAINT MONO (2660 760);
DISPLAY INVISIBLE (2660 760);
FORCEPROP 1 LASTPIN (2650 750) BN 3
J 2
(2662 758);
DISPLAY 0.680851 (2662 758);
PAINT GREEN (2662 758);
FORCEPROP 2 LAST CDS_LIB standard
J 0
(2600 750);
DISPLAY INVISIBLE (2600 750);
FORCEPROP 1 LAST BODY_TYPE PLUMBING
J 2
(2600 800);
DISPLAY 0.872340 (2600 800);
PAINT GREEN (2600 800);
DISPLAY INVISIBLE (2600 800);
FORCEPROP 1 LAST HDL_TAP TRUE
J 2
(2275 625);
DISPLAY 0.872340 (2275 625);
DISPLAY INVISIBLE (2275 625);
FORCEPROP 1 LAST PATH I322
J 2
(2602 750);
DISPLAY 0.872340 (2602 750);
PAINT GREEN (2602 750);
DISPLAY INVISIBLE (2602 750);
FORCEADD TAP..1
R 2
(2600 950);
FORCEPROP 3 LASTPIN (2650 950) SIG_NAME P5E_CPU1_PE1_TX_DP<4>
J 0
(2660 960);
DISPLAY 0.659574 (2660 960);
PAINT MONO (2660 960);
DISPLAY INVISIBLE (2660 960);
FORCEPROP 1 LASTPIN (2650 950) BN 4
J 2
(2662 958);
DISPLAY 0.680851 (2662 958);
PAINT GREEN (2662 958);
FORCEPROP 2 LAST CDS_LIB standard
J 0
(2600 950);
DISPLAY INVISIBLE (2600 950);
FORCEPROP 1 LAST BODY_TYPE PLUMBING
J 2
(2600 1000);
DISPLAY 0.872340 (2600 1000);
PAINT GREEN (2600 1000);
DISPLAY INVISIBLE (2600 1000);
FORCEPROP 1 LAST HDL_TAP TRUE
J 2
(2275 825);
DISPLAY 0.872340 (2275 825);
DISPLAY INVISIBLE (2275 825);
FORCEPROP 1 LAST PATH I323
J 2
(2602 950);
DISPLAY 0.872340 (2602 950);
PAINT GREEN (2602 950);
DISPLAY INVISIBLE (2602 950);
FORCEADD TAP..1
R 2
(2850 600);
FORCEPROP 3 LASTPIN (2900 600) SIG_NAME P5E_CPU1_PE1_TX_DN<2>
J 0
(2910 610);
DISPLAY 0.659574 (2910 610);
PAINT MONO (2910 610);
DISPLAY INVISIBLE (2910 610);
FORCEPROP 1 LASTPIN (2900 600) BN 2
J 2
(2912 608);
DISPLAY 0.680851 (2912 608);
PAINT GREEN (2912 608);
FORCEPROP 2 LAST CDS_LIB standard
J 0
(2850 600);
DISPLAY INVISIBLE (2850 600);
FORCEPROP 1 LAST BODY_TYPE PLUMBING
J 2
(2850 650);
DISPLAY 0.872340 (2850 650);
PAINT GREEN (2850 650);
DISPLAY INVISIBLE (2850 650);
FORCEPROP 1 LAST HDL_TAP TRUE
J 2
(2525 475);
DISPLAY 0.872340 (2525 475);
DISPLAY INVISIBLE (2525 475);
FORCEPROP 1 LAST PATH I324
J 2
(2852 600);
DISPLAY 0.872340 (2852 600);
PAINT GREEN (2852 600);
DISPLAY INVISIBLE (2852 600);
FORCEADD TAP..1
R 2
(2850 800);
FORCEPROP 3 LASTPIN (2900 800) SIG_NAME P5E_CPU1_PE1_TX_DN<3>
J 0
(2910 810);
DISPLAY 0.659574 (2910 810);
PAINT MONO (2910 810);
DISPLAY INVISIBLE (2910 810);
FORCEPROP 1 LASTPIN (2900 800) BN 3
J 2
(2912 808);
DISPLAY 0.680851 (2912 808);
PAINT GREEN (2912 808);
FORCEPROP 2 LAST CDS_LIB standard
J 0
(2850 800);
DISPLAY INVISIBLE (2850 800);
FORCEPROP 1 LAST BODY_TYPE PLUMBING
J 2
(2850 850);
DISPLAY 0.872340 (2850 850);
PAINT GREEN (2850 850);
DISPLAY INVISIBLE (2850 850);
FORCEPROP 1 LAST HDL_TAP TRUE
J 2
(2525 675);
DISPLAY 0.872340 (2525 675);
DISPLAY INVISIBLE (2525 675);
FORCEPROP 1 LAST PATH I325
J 2
(2852 800);
DISPLAY 0.872340 (2852 800);
PAINT GREEN (2852 800);
DISPLAY INVISIBLE (2852 800);
FORCEADD TAP..1
R 2
(2850 1000);
FORCEPROP 3 LASTPIN (2900 1000) SIG_NAME P5E_CPU1_PE1_TX_DN<4>
J 0
(2910 1010);
DISPLAY 0.659574 (2910 1010);
PAINT MONO (2910 1010);
DISPLAY INVISIBLE (2910 1010);
FORCEPROP 1 LASTPIN (2900 1000) BN 4
J 2
(2912 1008);
DISPLAY 0.680851 (2912 1008);
PAINT GREEN (2912 1008);
FORCEPROP 2 LAST CDS_LIB standard
J 0
(2850 1000);
DISPLAY INVISIBLE (2850 1000);
FORCEPROP 1 LAST BODY_TYPE PLUMBING
J 2
(2850 1050);
DISPLAY 0.872340 (2850 1050);
PAINT GREEN (2850 1050);
DISPLAY INVISIBLE (2850 1050);
FORCEPROP 1 LAST HDL_TAP TRUE
J 2
(2525 875);
DISPLAY 0.872340 (2525 875);
DISPLAY INVISIBLE (2525 875);
FORCEPROP 1 LAST PATH I326
J 2
(2852 1000);
DISPLAY 0.872340 (2852 1000);
PAINT GREEN (2852 1000);
DISPLAY INVISIBLE (2852 1000);
FORCEADD TAP..1
R 2
(2600 1150);
FORCEPROP 3 LASTPIN (2650 1150) SIG_NAME P5E_CPU1_PE1_TX_DP<5>
J 0
(2660 1160);
DISPLAY 0.659574 (2660 1160);
PAINT MONO (2660 1160);
DISPLAY INVISIBLE (2660 1160);
FORCEPROP 1 LASTPIN (2650 1150) BN 5
J 2
(2662 1158);
DISPLAY 0.680851 (2662 1158);
PAINT GREEN (2662 1158);
FORCEPROP 2 LAST CDS_LIB standard
J 0
(2600 1150);
DISPLAY INVISIBLE (2600 1150);
FORCEPROP 1 LAST BODY_TYPE PLUMBING
J 2
(2600 1200);
DISPLAY 0.872340 (2600 1200);
PAINT GREEN (2600 1200);
DISPLAY INVISIBLE (2600 1200);
FORCEPROP 1 LAST HDL_TAP TRUE
J 2
(2275 1025);
DISPLAY 0.872340 (2275 1025);
DISPLAY INVISIBLE (2275 1025);
FORCEPROP 1 LAST PATH I327
J 2
(2602 1150);
DISPLAY 0.872340 (2602 1150);
PAINT GREEN (2602 1150);
DISPLAY INVISIBLE (2602 1150);
FORCEADD TAP..1
R 2
(2600 1350);
FORCEPROP 3 LASTPIN (2650 1350) SIG_NAME P5E_CPU1_PE1_TX_DP<6>
J 0
(2660 1360);
DISPLAY 0.659574 (2660 1360);
PAINT MONO (2660 1360);
DISPLAY INVISIBLE (2660 1360);
FORCEPROP 1 LASTPIN (2650 1350) BN 6
J 2
(2662 1358);
DISPLAY 0.680851 (2662 1358);
PAINT GREEN (2662 1358);
FORCEPROP 2 LAST CDS_LIB standard
J 0
(2600 1350);
DISPLAY INVISIBLE (2600 1350);
FORCEPROP 1 LAST BODY_TYPE PLUMBING
J 2
(2600 1400);
DISPLAY 0.872340 (2600 1400);
PAINT GREEN (2600 1400);
DISPLAY INVISIBLE (2600 1400);
FORCEPROP 1 LAST HDL_TAP TRUE
J 2
(2275 1225);
DISPLAY 0.872340 (2275 1225);
DISPLAY INVISIBLE (2275 1225);
FORCEPROP 1 LAST PATH I328
J 2
(2602 1350);
DISPLAY 0.872340 (2602 1350);
PAINT GREEN (2602 1350);
DISPLAY INVISIBLE (2602 1350);
FORCEADD TAP..1
R 2
(2850 1200);
FORCEPROP 3 LASTPIN (2900 1200) SIG_NAME P5E_CPU1_PE1_TX_DN<5>
J 0
(2910 1210);
DISPLAY 0.659574 (2910 1210);
PAINT MONO (2910 1210);
DISPLAY INVISIBLE (2910 1210);
FORCEPROP 1 LASTPIN (2900 1200) BN 5
J 2
(2912 1208);
DISPLAY 0.680851 (2912 1208);
PAINT GREEN (2912 1208);
FORCEPROP 2 LAST CDS_LIB standard
J 0
(2850 1200);
DISPLAY INVISIBLE (2850 1200);
FORCEPROP 1 LAST BODY_TYPE PLUMBING
J 2
(2850 1250);
DISPLAY 0.872340 (2850 1250);
PAINT GREEN (2850 1250);
DISPLAY INVISIBLE (2850 1250);
FORCEPROP 1 LAST HDL_TAP TRUE
J 2
(2525 1075);
DISPLAY 0.872340 (2525 1075);
DISPLAY INVISIBLE (2525 1075);
FORCEPROP 1 LAST PATH I329
J 2
(2852 1200);
DISPLAY 0.872340 (2852 1200);
PAINT GREEN (2852 1200);
DISPLAY INVISIBLE (2852 1200);
FORCEADD TAP..1
R 2
(2850 1400);
FORCEPROP 3 LASTPIN (2900 1400) SIG_NAME P5E_CPU1_PE1_TX_DN<6>
J 0
(2910 1410);
DISPLAY 0.659574 (2910 1410);
PAINT MONO (2910 1410);
DISPLAY INVISIBLE (2910 1410);
FORCEPROP 1 LASTPIN (2900 1400) BN 6
J 2
(2912 1408);
DISPLAY 0.680851 (2912 1408);
PAINT GREEN (2912 1408);
FORCEPROP 2 LAST CDS_LIB standard
J 0
(2850 1400);
DISPLAY INVISIBLE (2850 1400);
FORCEPROP 1 LAST BODY_TYPE PLUMBING
J 2
(2850 1450);
DISPLAY 0.872340 (2850 1450);
PAINT GREEN (2850 1450);
DISPLAY INVISIBLE (2850 1450);
FORCEPROP 1 LAST HDL_TAP TRUE
J 2
(2525 1275);
DISPLAY 0.872340 (2525 1275);
DISPLAY INVISIBLE (2525 1275);
FORCEPROP 1 LAST PATH I330
J 2
(2852 1400);
DISPLAY 0.872340 (2852 1400);
PAINT GREEN (2852 1400);
DISPLAY INVISIBLE (2852 1400);
FORCEADD TAP..1
R 2
(2600 1550);
FORCEPROP 3 LASTPIN (2650 1550) SIG_NAME P5E_CPU1_PE1_TX_DP<7>
J 0
(2660 1560);
DISPLAY 0.659574 (2660 1560);
PAINT MONO (2660 1560);
DISPLAY INVISIBLE (2660 1560);
FORCEPROP 1 LASTPIN (2650 1550) BN 7
J 2
(2662 1558);
DISPLAY 0.680851 (2662 1558);
PAINT GREEN (2662 1558);
FORCEPROP 2 LAST CDS_LIB standard
J 0
(2600 1550);
DISPLAY INVISIBLE (2600 1550);
FORCEPROP 1 LAST BODY_TYPE PLUMBING
J 2
(2600 1600);
DISPLAY 0.872340 (2600 1600);
PAINT GREEN (2600 1600);
DISPLAY INVISIBLE (2600 1600);
FORCEPROP 1 LAST HDL_TAP TRUE
J 2
(2275 1425);
DISPLAY 0.872340 (2275 1425);
DISPLAY INVISIBLE (2275 1425);
FORCEPROP 1 LAST PATH I331
J 2
(2602 1550);
DISPLAY 0.872340 (2602 1550);
PAINT GREEN (2602 1550);
DISPLAY INVISIBLE (2602 1550);
FORCEADD TAP..1
R 2
(2850 1600);
FORCEPROP 3 LASTPIN (2900 1600) SIG_NAME P5E_CPU1_PE1_TX_DN<7>
J 0
(2910 1610);
DISPLAY 0.659574 (2910 1610);
PAINT MONO (2910 1610);
DISPLAY INVISIBLE (2910 1610);
FORCEPROP 1 LASTPIN (2900 1600) BN 7
J 2
(2912 1608);
DISPLAY 0.680851 (2912 1608);
PAINT GREEN (2912 1608);
FORCEPROP 2 LAST CDS_LIB standard
J 0
(2850 1600);
DISPLAY INVISIBLE (2850 1600);
FORCEPROP 1 LAST BODY_TYPE PLUMBING
J 2
(2850 1650);
DISPLAY 0.872340 (2850 1650);
PAINT GREEN (2850 1650);
DISPLAY INVISIBLE (2850 1650);
FORCEPROP 1 LAST HDL_TAP TRUE
J 2
(2525 1475);
DISPLAY 0.872340 (2525 1475);
DISPLAY INVISIBLE (2525 1475);
FORCEPROP 1 LAST PATH I332
J 2
(2852 1600);
DISPLAY 0.872340 (2852 1600);
PAINT GREEN (2852 1600);
DISPLAY INVISIBLE (2852 1600);
FORCEADD Q_CAP_DIFFBUS..2
R 2
(3575 200);
FORCEPROP 1 LAST PART_NUMBER SP_CH4221MEE01
J 2
(3459 288);
DISPLAY 0.574468 (3459 288);
PAINT GREEN (3459 288);
DISPLAY INVISIBLE (3459 288);
FORCEPROP 2 LAST VALUE DIFF BUS_0.22UF
J 2
(3425 200);
DISPLAY 0.553191 (3425 200);
FORCEPROP 1 LAST $LOCATION C836
J 2
(3809 217);
DISPLAY 0.723404 (3809 217);
PAINT GREEN (3809 217);
FORCEPROP 2 LASTPIN (3650 200) $PN 1
J 0
(3660 210);
DISPLAY 0.808511 (3660 210);
FORCEPROP 2 LASTPIN (3500 200) $PN 2
J 2
(3490 210);
DISPLAY 0.808511 (3490 210);
FORCEPROP 1 LAST PIN_NAMES_ROTATE TRUE
J 2
(3575 200);
DISPLAY 0.489362 (3575 200);
PAINT GREEN (3575 200);
DISPLAY INVISIBLE (3575 200);
FORCEPROP 2 LAST CDS_LIB pure_quanta
J 2
(3575 200);
DISPLAY INVISIBLE (3575 200);
FORCEPROP 1 LAST CDS_LMAN_SYM_OUTLINE -25,50,25,-50
J 2
(3575 200);
DISPLAY 0.468085 (3575 200);
PAINT GREEN (3575 200);
DISPLAY INVISIBLE (3575 200);
FORCEPROP 2 LAST VOLTAGE 6.3V
J 2
(3225 250);
DISPLAY 0.553191 (3225 250);
DISPLAY INVISIBLE (3225 250);
FORCEPROP 1 LAST MATERIAL X6S
J 2
(3584 279);
DISPLAY 0.574468 (3584 279);
PAINT GREEN (3584 279);
DISPLAY INVISIBLE (3584 279);
FORCEPROP 2 LAST PACK_TYPE C0201
J 2
(3400 250);
DISPLAY 0.553191 (3400 250);
DISPLAY INVISIBLE (3400 250);
FORCEPROP 2 LAST TOLERANCE 20%
J 2
(3500 250);
DISPLAY 0.553191 (3500 250);
DISPLAY INVISIBLE (3500 250);
FORCEPROP 1 LAST PATH I333
J 2
(3575 200);
DISPLAY 0.723404 (3575 200);
DISPLAY INVISIBLE (3575 200);
FORCEPROP 1 LAST $LOCATION C836
J 0
(3825 275);
DISPLAY 1.021277 (3825 275);
DISPLAY INVISIBLE (3825 275);
FORCEPROP 2 LAST CDS_LOCATION C836
J 0
(3825 275);
DISPLAY 1.021277 (3825 275);
DISPLAY INVISIBLE (3825 275);
FORCEPROP 2 LAST $SEC 1
J 2
(3750 275);
DISPLAY 0.680851 (3750 275);
PAINT MONO (3750 275);
DISPLAY INVISIBLE (3750 275);
FORCEPROP 2 LAST CDS_SEC 1
J 2
(3750 275);
DISPLAY 0.680851 (3750 275);
DISPLAY INVISIBLE (3750 275);
FORCEADD Q_CAP_DIFFBUS..2
R 2
(3575 150);
FORCEPROP 1 LAST PART_NUMBER SP_CH4221MEE01
J 2
(3459 238);
DISPLAY 0.574468 (3459 238);
PAINT GREEN (3459 238);
DISPLAY INVISIBLE (3459 238);
FORCEPROP 2 LAST VALUE DIFF BUS_0.22UF
J 2
(3425 150);
DISPLAY 0.553191 (3425 150);
FORCEPROP 1 LAST $LOCATION C837
J 2
(3809 167);
DISPLAY 0.723404 (3809 167);
PAINT GREEN (3809 167);
FORCEPROP 2 LASTPIN (3650 150) $PN 1
J 0
(3660 160);
DISPLAY 0.808511 (3660 160);
FORCEPROP 2 LASTPIN (3500 150) $PN 2
J 2
(3490 160);
DISPLAY 0.808511 (3490 160);
FORCEPROP 1 LAST PIN_NAMES_ROTATE TRUE
J 2
(3575 150);
DISPLAY 0.489362 (3575 150);
PAINT GREEN (3575 150);
DISPLAY INVISIBLE (3575 150);
FORCEPROP 2 LAST CDS_LIB pure_quanta
J 2
(3575 150);
DISPLAY INVISIBLE (3575 150);
FORCEPROP 1 LAST CDS_LMAN_SYM_OUTLINE -25,50,25,-50
J 2
(3575 150);
DISPLAY 0.468085 (3575 150);
PAINT GREEN (3575 150);
DISPLAY INVISIBLE (3575 150);
FORCEPROP 2 LAST VOLTAGE 6.3V
J 2
(3225 200);
DISPLAY 0.553191 (3225 200);
DISPLAY INVISIBLE (3225 200);
FORCEPROP 1 LAST MATERIAL X6S
J 2
(3584 229);
DISPLAY 0.574468 (3584 229);
PAINT GREEN (3584 229);
DISPLAY INVISIBLE (3584 229);
FORCEPROP 2 LAST PACK_TYPE C0201
J 2
(3400 200);
DISPLAY 0.553191 (3400 200);
DISPLAY INVISIBLE (3400 200);
FORCEPROP 2 LAST TOLERANCE 20%
J 2
(3500 200);
DISPLAY 0.553191 (3500 200);
DISPLAY INVISIBLE (3500 200);
FORCEPROP 1 LAST PATH I334
J 2
(3575 150);
DISPLAY 0.723404 (3575 150);
DISPLAY INVISIBLE (3575 150);
FORCEPROP 1 LAST $LOCATION C837
J 0
(3825 225);
DISPLAY 1.021277 (3825 225);
DISPLAY INVISIBLE (3825 225);
FORCEPROP 2 LAST CDS_LOCATION C837
J 0
(3825 225);
DISPLAY 1.021277 (3825 225);
DISPLAY INVISIBLE (3825 225);
FORCEPROP 2 LAST $SEC 1
J 2
(3750 225);
DISPLAY 0.680851 (3750 225);
PAINT MONO (3750 225);
DISPLAY INVISIBLE (3750 225);
FORCEPROP 2 LAST CDS_SEC 1
J 2
(3750 225);
DISPLAY 0.680851 (3750 225);
DISPLAY INVISIBLE (3750 225);
FORCEADD Q_CAP_DIFFBUS..2
R 2
(3575 400);
FORCEPROP 1 LAST PART_NUMBER SP_CH4221MEE01
J 2
(3459 488);
DISPLAY 0.574468 (3459 488);
PAINT GREEN (3459 488);
DISPLAY INVISIBLE (3459 488);
FORCEPROP 2 LAST VALUE DIFF BUS_0.22UF
J 2
(3425 400);
DISPLAY 0.553191 (3425 400);
FORCEPROP 1 LAST $LOCATION C834
J 2
(3809 417);
DISPLAY 0.723404 (3809 417);
PAINT GREEN (3809 417);
FORCEPROP 2 LASTPIN (3650 400) $PN 1
J 0
(3660 410);
DISPLAY 0.808511 (3660 410);
FORCEPROP 2 LASTPIN (3500 400) $PN 2
J 2
(3490 410);
DISPLAY 0.808511 (3490 410);
FORCEPROP 1 LAST PIN_NAMES_ROTATE TRUE
J 2
(3575 400);
DISPLAY 0.489362 (3575 400);
PAINT GREEN (3575 400);
DISPLAY INVISIBLE (3575 400);
FORCEPROP 1 LAST CDS_LMAN_SYM_OUTLINE -25,50,25,-50
J 2
(3575 400);
DISPLAY 0.468085 (3575 400);
PAINT GREEN (3575 400);
DISPLAY INVISIBLE (3575 400);
FORCEPROP 2 LAST CDS_LIB pure_quanta
J 2
(3575 400);
DISPLAY INVISIBLE (3575 400);
FORCEPROP 2 LAST VOLTAGE 6.3V
J 2
(3225 450);
DISPLAY 0.553191 (3225 450);
DISPLAY INVISIBLE (3225 450);
FORCEPROP 1 LAST MATERIAL X6S
J 2
(3584 479);
DISPLAY 0.574468 (3584 479);
PAINT GREEN (3584 479);
DISPLAY INVISIBLE (3584 479);
FORCEPROP 2 LAST PACK_TYPE C0201
J 2
(3400 450);
DISPLAY 0.553191 (3400 450);
DISPLAY INVISIBLE (3400 450);
FORCEPROP 2 LAST TOLERANCE 20%
J 2
(3500 450);
DISPLAY 0.553191 (3500 450);
DISPLAY INVISIBLE (3500 450);
FORCEPROP 1 LAST PATH I335
J 2
(3575 400);
DISPLAY 0.723404 (3575 400);
DISPLAY INVISIBLE (3575 400);
FORCEPROP 1 LAST $LOCATION C834
J 0
(3825 475);
DISPLAY 1.021277 (3825 475);
DISPLAY INVISIBLE (3825 475);
FORCEPROP 2 LAST CDS_LOCATION C834
J 0
(3825 475);
DISPLAY 1.021277 (3825 475);
DISPLAY INVISIBLE (3825 475);
FORCEPROP 2 LAST $SEC 1
J 2
(3750 475);
DISPLAY 0.680851 (3750 475);
PAINT MONO (3750 475);
DISPLAY INVISIBLE (3750 475);
FORCEPROP 2 LAST CDS_SEC 1
J 2
(3750 475);
DISPLAY 0.680851 (3750 475);
DISPLAY INVISIBLE (3750 475);
FORCEADD Q_CAP_DIFFBUS..2
R 2
(3575 350);
FORCEPROP 1 LAST PART_NUMBER SP_CH4221MEE01
J 2
(3459 438);
DISPLAY 0.574468 (3459 438);
PAINT GREEN (3459 438);
DISPLAY INVISIBLE (3459 438);
FORCEPROP 2 LAST VALUE DIFF BUS_0.22UF
J 2
(3425 350);
DISPLAY 0.553191 (3425 350);
FORCEPROP 1 LAST $LOCATION C835
J 2
(3809 367);
DISPLAY 0.723404 (3809 367);
PAINT GREEN (3809 367);
FORCEPROP 2 LASTPIN (3650 350) $PN 1
J 0
(3660 360);
DISPLAY 0.808511 (3660 360);
FORCEPROP 2 LASTPIN (3500 350) $PN 2
J 2
(3490 360);
DISPLAY 0.808511 (3490 360);
FORCEPROP 1 LAST PIN_NAMES_ROTATE TRUE
J 2
(3575 350);
DISPLAY 0.489362 (3575 350);
PAINT GREEN (3575 350);
DISPLAY INVISIBLE (3575 350);
FORCEPROP 2 LAST CDS_LIB pure_quanta
J 2
(3575 350);
DISPLAY INVISIBLE (3575 350);
FORCEPROP 1 LAST CDS_LMAN_SYM_OUTLINE -25,50,25,-50
J 2
(3575 350);
DISPLAY 0.468085 (3575 350);
PAINT GREEN (3575 350);
DISPLAY INVISIBLE (3575 350);
FORCEPROP 2 LAST VOLTAGE 6.3V
J 2
(3225 400);
DISPLAY 0.553191 (3225 400);
DISPLAY INVISIBLE (3225 400);
FORCEPROP 1 LAST MATERIAL X6S
J 2
(3584 429);
DISPLAY 0.574468 (3584 429);
PAINT GREEN (3584 429);
DISPLAY INVISIBLE (3584 429);
FORCEPROP 2 LAST PACK_TYPE C0201
J 2
(3400 400);
DISPLAY 0.553191 (3400 400);
DISPLAY INVISIBLE (3400 400);
FORCEPROP 2 LAST TOLERANCE 20%
J 2
(3500 400);
DISPLAY 0.553191 (3500 400);
DISPLAY INVISIBLE (3500 400);
FORCEPROP 1 LAST PATH I336
J 2
(3575 350);
DISPLAY 0.723404 (3575 350);
DISPLAY INVISIBLE (3575 350);
FORCEPROP 1 LAST $LOCATION C835
J 0
(3825 425);
DISPLAY 1.021277 (3825 425);
DISPLAY INVISIBLE (3825 425);
FORCEPROP 2 LAST CDS_LOCATION C835
J 0
(3825 425);
DISPLAY 1.021277 (3825 425);
DISPLAY INVISIBLE (3825 425);
FORCEPROP 2 LAST $SEC 1
J 2
(3750 425);
DISPLAY 0.680851 (3750 425);
PAINT MONO (3750 425);
DISPLAY INVISIBLE (3750 425);
FORCEPROP 2 LAST CDS_SEC 1
J 2
(3750 425);
DISPLAY 0.680851 (3750 425);
DISPLAY INVISIBLE (3750 425);
FORCEADD Q_CAP_DIFFBUS..2
R 2
(3575 750);
FORCEPROP 1 LAST PART_NUMBER SP_CH4221MEE01
J 2
(3459 838);
DISPLAY 0.574468 (3459 838);
PAINT GREEN (3459 838);
DISPLAY INVISIBLE (3459 838);
FORCEPROP 2 LAST VALUE DIFF BUS_0.22UF
J 2
(3425 750);
DISPLAY 0.553191 (3425 750);
FORCEPROP 1 LAST $LOCATION C831
J 2
(3809 767);
DISPLAY 0.723404 (3809 767);
PAINT GREEN (3809 767);
FORCEPROP 2 LASTPIN (3650 750) $PN 1
J 0
(3660 760);
DISPLAY 0.808511 (3660 760);
FORCEPROP 2 LASTPIN (3500 750) $PN 2
J 2
(3490 760);
DISPLAY 0.808511 (3490 760);
FORCEPROP 1 LAST PIN_NAMES_ROTATE TRUE
J 2
(3575 750);
DISPLAY 0.489362 (3575 750);
PAINT GREEN (3575 750);
DISPLAY INVISIBLE (3575 750);
FORCEPROP 1 LAST CDS_LMAN_SYM_OUTLINE -25,50,25,-50
J 2
(3575 750);
DISPLAY 0.468085 (3575 750);
PAINT GREEN (3575 750);
DISPLAY INVISIBLE (3575 750);
FORCEPROP 2 LAST CDS_LIB pure_quanta
J 2
(3575 750);
DISPLAY INVISIBLE (3575 750);
FORCEPROP 2 LAST VOLTAGE 6.3V
J 2
(3225 800);
DISPLAY 0.553191 (3225 800);
DISPLAY INVISIBLE (3225 800);
FORCEPROP 1 LAST MATERIAL X6S
J 2
(3584 829);
DISPLAY 0.574468 (3584 829);
PAINT GREEN (3584 829);
DISPLAY INVISIBLE (3584 829);
FORCEPROP 2 LAST PACK_TYPE C0201
J 2
(3400 800);
DISPLAY 0.553191 (3400 800);
DISPLAY INVISIBLE (3400 800);
FORCEPROP 2 LAST TOLERANCE 20%
J 2
(3500 800);
DISPLAY 0.553191 (3500 800);
DISPLAY INVISIBLE (3500 800);
FORCEPROP 1 LAST PATH I337
J 2
(3575 750);
DISPLAY 0.723404 (3575 750);
DISPLAY INVISIBLE (3575 750);
FORCEPROP 1 LAST $LOCATION C831
J 0
(3825 825);
DISPLAY 1.021277 (3825 825);
DISPLAY INVISIBLE (3825 825);
FORCEPROP 2 LAST CDS_LOCATION C831
J 0
(3825 825);
DISPLAY 1.021277 (3825 825);
DISPLAY INVISIBLE (3825 825);
FORCEPROP 2 LAST $SEC 1
J 2
(3750 825);
DISPLAY 0.680851 (3750 825);
PAINT MONO (3750 825);
DISPLAY INVISIBLE (3750 825);
FORCEPROP 2 LAST CDS_SEC 1
J 2
(3750 825);
DISPLAY 0.680851 (3750 825);
DISPLAY INVISIBLE (3750 825);
FORCEADD Q_CAP_DIFFBUS..2
R 2
(3575 600);
FORCEPROP 1 LAST PART_NUMBER SP_CH4221MEE01
J 2
(3459 688);
DISPLAY 0.574468 (3459 688);
PAINT GREEN (3459 688);
DISPLAY INVISIBLE (3459 688);
FORCEPROP 2 LAST VALUE DIFF BUS_0.22UF
J 2
(3425 600);
DISPLAY 0.553191 (3425 600);
FORCEPROP 1 LAST $LOCATION C832
J 2
(3809 617);
DISPLAY 0.723404 (3809 617);
PAINT GREEN (3809 617);
FORCEPROP 2 LASTPIN (3650 600) $PN 1
J 0
(3660 610);
DISPLAY 0.808511 (3660 610);
FORCEPROP 2 LASTPIN (3500 600) $PN 2
J 2
(3490 610);
DISPLAY 0.808511 (3490 610);
FORCEPROP 1 LAST PIN_NAMES_ROTATE TRUE
J 2
(3575 600);
DISPLAY 0.489362 (3575 600);
PAINT GREEN (3575 600);
DISPLAY INVISIBLE (3575 600);
FORCEPROP 2 LAST CDS_LIB pure_quanta
J 2
(3575 600);
DISPLAY INVISIBLE (3575 600);
FORCEPROP 1 LAST CDS_LMAN_SYM_OUTLINE -25,50,25,-50
J 2
(3575 600);
DISPLAY 0.468085 (3575 600);
PAINT GREEN (3575 600);
DISPLAY INVISIBLE (3575 600);
FORCEPROP 2 LAST VOLTAGE 6.3V
J 2
(3225 650);
DISPLAY 0.553191 (3225 650);
DISPLAY INVISIBLE (3225 650);
FORCEPROP 1 LAST MATERIAL X6S
J 2
(3584 679);
DISPLAY 0.574468 (3584 679);
PAINT GREEN (3584 679);
DISPLAY INVISIBLE (3584 679);
FORCEPROP 2 LAST PACK_TYPE C0201
J 2
(3400 650);
DISPLAY 0.553191 (3400 650);
DISPLAY INVISIBLE (3400 650);
FORCEPROP 2 LAST TOLERANCE 20%
J 2
(3500 650);
DISPLAY 0.553191 (3500 650);
DISPLAY INVISIBLE (3500 650);
FORCEPROP 1 LAST PATH I338
J 2
(3575 600);
DISPLAY 0.723404 (3575 600);
DISPLAY INVISIBLE (3575 600);
FORCEPROP 1 LAST $LOCATION C832
J 0
(3825 675);
DISPLAY 1.021277 (3825 675);
DISPLAY INVISIBLE (3825 675);
FORCEPROP 2 LAST CDS_LOCATION C832
J 0
(3825 675);
DISPLAY 1.021277 (3825 675);
DISPLAY INVISIBLE (3825 675);
FORCEPROP 2 LAST $SEC 1
J 2
(3750 675);
DISPLAY 0.680851 (3750 675);
PAINT MONO (3750 675);
DISPLAY INVISIBLE (3750 675);
FORCEPROP 2 LAST CDS_SEC 1
J 2
(3750 675);
DISPLAY 0.680851 (3750 675);
DISPLAY INVISIBLE (3750 675);
FORCEADD Q_CAP_DIFFBUS..2
R 2
(3575 550);
FORCEPROP 1 LAST PART_NUMBER SP_CH4221MEE01
J 2
(3459 638);
DISPLAY 0.574468 (3459 638);
PAINT GREEN (3459 638);
DISPLAY INVISIBLE (3459 638);
FORCEPROP 2 LAST VALUE DIFF BUS_0.22UF
J 2
(3425 550);
DISPLAY 0.553191 (3425 550);
FORCEPROP 1 LAST $LOCATION C833
J 2
(3809 567);
DISPLAY 0.723404 (3809 567);
PAINT GREEN (3809 567);
FORCEPROP 2 LASTPIN (3650 550) $PN 1
J 0
(3660 560);
DISPLAY 0.808511 (3660 560);
FORCEPROP 2 LASTPIN (3500 550) $PN 2
J 2
(3490 560);
DISPLAY 0.808511 (3490 560);
FORCEPROP 1 LAST PIN_NAMES_ROTATE TRUE
J 2
(3575 550);
DISPLAY 0.489362 (3575 550);
PAINT GREEN (3575 550);
DISPLAY INVISIBLE (3575 550);
FORCEPROP 2 LAST CDS_LIB pure_quanta
J 2
(3575 550);
DISPLAY INVISIBLE (3575 550);
FORCEPROP 1 LAST CDS_LMAN_SYM_OUTLINE -25,50,25,-50
J 2
(3575 550);
DISPLAY 0.468085 (3575 550);
PAINT GREEN (3575 550);
DISPLAY INVISIBLE (3575 550);
FORCEPROP 2 LAST VOLTAGE 6.3V
J 2
(3225 600);
DISPLAY 0.553191 (3225 600);
DISPLAY INVISIBLE (3225 600);
FORCEPROP 1 LAST MATERIAL X6S
J 2
(3584 629);
DISPLAY 0.574468 (3584 629);
PAINT GREEN (3584 629);
DISPLAY INVISIBLE (3584 629);
FORCEPROP 2 LAST PACK_TYPE C0201
J 2
(3400 600);
DISPLAY 0.553191 (3400 600);
DISPLAY INVISIBLE (3400 600);
FORCEPROP 2 LAST TOLERANCE 20%
J 2
(3500 600);
DISPLAY 0.553191 (3500 600);
DISPLAY INVISIBLE (3500 600);
FORCEPROP 1 LAST PATH I339
J 2
(3575 550);
DISPLAY 0.723404 (3575 550);
DISPLAY INVISIBLE (3575 550);
FORCEPROP 1 LAST $LOCATION C833
J 0
(3825 625);
DISPLAY 1.021277 (3825 625);
DISPLAY INVISIBLE (3825 625);
FORCEPROP 2 LAST CDS_LOCATION C833
J 0
(3825 625);
DISPLAY 1.021277 (3825 625);
DISPLAY INVISIBLE (3825 625);
FORCEPROP 2 LAST $SEC 1
J 2
(3750 625);
DISPLAY 0.680851 (3750 625);
PAINT MONO (3750 625);
DISPLAY INVISIBLE (3750 625);
FORCEPROP 2 LAST CDS_SEC 1
J 2
(3750 625);
DISPLAY 0.680851 (3750 625);
DISPLAY INVISIBLE (3750 625);
FORCEADD Q_CAP_DIFFBUS..2
R 2
(3575 1000);
FORCEPROP 1 LAST PART_NUMBER SP_CH4221MEE01
J 2
(3459 1088);
DISPLAY 0.574468 (3459 1088);
PAINT GREEN (3459 1088);
DISPLAY INVISIBLE (3459 1088);
FORCEPROP 2 LAST VALUE DIFF BUS_0.22UF
J 2
(3425 1000);
DISPLAY 0.553191 (3425 1000);
FORCEPROP 1 LAST $LOCATION C828
J 2
(3809 1017);
DISPLAY 0.723404 (3809 1017);
PAINT GREEN (3809 1017);
FORCEPROP 2 LASTPIN (3650 1000) $PN 1
J 0
(3660 1010);
DISPLAY 0.808511 (3660 1010);
FORCEPROP 2 LASTPIN (3500 1000) $PN 2
J 2
(3490 1010);
DISPLAY 0.808511 (3490 1010);
FORCEPROP 1 LAST PIN_NAMES_ROTATE TRUE
J 2
(3575 1000);
DISPLAY 0.489362 (3575 1000);
PAINT GREEN (3575 1000);
DISPLAY INVISIBLE (3575 1000);
FORCEPROP 2 LAST CDS_LIB pure_quanta
J 2
(3575 1000);
DISPLAY INVISIBLE (3575 1000);
FORCEPROP 1 LAST CDS_LMAN_SYM_OUTLINE -25,50,25,-50
J 2
(3575 1000);
DISPLAY 0.468085 (3575 1000);
PAINT GREEN (3575 1000);
DISPLAY INVISIBLE (3575 1000);
FORCEPROP 2 LAST VOLTAGE 6.3V
J 2
(3225 1050);
DISPLAY 0.553191 (3225 1050);
DISPLAY INVISIBLE (3225 1050);
FORCEPROP 1 LAST MATERIAL X6S
J 2
(3584 1079);
DISPLAY 0.574468 (3584 1079);
PAINT GREEN (3584 1079);
DISPLAY INVISIBLE (3584 1079);
FORCEPROP 2 LAST PACK_TYPE C0201
J 2
(3400 1050);
DISPLAY 0.553191 (3400 1050);
DISPLAY INVISIBLE (3400 1050);
FORCEPROP 2 LAST TOLERANCE 20%
J 2
(3500 1050);
DISPLAY 0.553191 (3500 1050);
DISPLAY INVISIBLE (3500 1050);
FORCEPROP 1 LAST PATH I340
J 2
(3575 1000);
DISPLAY 0.723404 (3575 1000);
DISPLAY INVISIBLE (3575 1000);
FORCEPROP 1 LAST $LOCATION C828
J 0
(3825 1075);
DISPLAY 1.021277 (3825 1075);
DISPLAY INVISIBLE (3825 1075);
FORCEPROP 2 LAST CDS_LOCATION C828
J 0
(3825 1075);
DISPLAY 1.021277 (3825 1075);
DISPLAY INVISIBLE (3825 1075);
FORCEPROP 2 LAST $SEC 1
J 2
(3750 1075);
DISPLAY 0.680851 (3750 1075);
PAINT MONO (3750 1075);
DISPLAY INVISIBLE (3750 1075);
FORCEPROP 2 LAST CDS_SEC 1
J 2
(3750 1075);
DISPLAY 0.680851 (3750 1075);
DISPLAY INVISIBLE (3750 1075);
FORCEADD Q_CAP_DIFFBUS..2
R 2
(3575 800);
FORCEPROP 1 LAST PART_NUMBER SP_CH4221MEE01
J 2
(3459 888);
DISPLAY 0.574468 (3459 888);
PAINT GREEN (3459 888);
DISPLAY INVISIBLE (3459 888);
FORCEPROP 2 LAST VALUE DIFF BUS_0.22UF
J 2
(3425 800);
DISPLAY 0.553191 (3425 800);
FORCEPROP 1 LAST $LOCATION C830
J 2
(3809 817);
DISPLAY 0.723404 (3809 817);
PAINT GREEN (3809 817);
FORCEPROP 2 LASTPIN (3650 800) $PN 1
J 0
(3660 810);
DISPLAY 0.808511 (3660 810);
FORCEPROP 2 LASTPIN (3500 800) $PN 2
J 2
(3490 810);
DISPLAY 0.808511 (3490 810);
FORCEPROP 1 LAST PIN_NAMES_ROTATE TRUE
J 2
(3575 800);
DISPLAY 0.489362 (3575 800);
PAINT GREEN (3575 800);
DISPLAY INVISIBLE (3575 800);
FORCEPROP 1 LAST CDS_LMAN_SYM_OUTLINE -25,50,25,-50
J 2
(3575 800);
DISPLAY 0.468085 (3575 800);
PAINT GREEN (3575 800);
DISPLAY INVISIBLE (3575 800);
FORCEPROP 2 LAST CDS_LIB pure_quanta
J 2
(3575 800);
DISPLAY INVISIBLE (3575 800);
FORCEPROP 2 LAST VOLTAGE 6.3V
J 2
(3225 850);
DISPLAY 0.553191 (3225 850);
DISPLAY INVISIBLE (3225 850);
FORCEPROP 1 LAST MATERIAL X6S
J 2
(3584 879);
DISPLAY 0.574468 (3584 879);
PAINT GREEN (3584 879);
DISPLAY INVISIBLE (3584 879);
FORCEPROP 2 LAST PACK_TYPE C0201
J 2
(3400 850);
DISPLAY 0.553191 (3400 850);
DISPLAY INVISIBLE (3400 850);
FORCEPROP 2 LAST TOLERANCE 20%
J 2
(3500 850);
DISPLAY 0.553191 (3500 850);
DISPLAY INVISIBLE (3500 850);
FORCEPROP 1 LAST PATH I341
J 2
(3575 800);
DISPLAY 0.723404 (3575 800);
DISPLAY INVISIBLE (3575 800);
FORCEPROP 1 LAST $LOCATION C830
J 0
(3825 875);
DISPLAY 1.021277 (3825 875);
DISPLAY INVISIBLE (3825 875);
FORCEPROP 2 LAST CDS_LOCATION C830
J 0
(3825 875);
DISPLAY 1.021277 (3825 875);
DISPLAY INVISIBLE (3825 875);
FORCEPROP 2 LAST $SEC 1
J 2
(3750 875);
DISPLAY 0.680851 (3750 875);
PAINT MONO (3750 875);
DISPLAY INVISIBLE (3750 875);
FORCEPROP 2 LAST CDS_SEC 1
J 2
(3750 875);
DISPLAY 0.680851 (3750 875);
DISPLAY INVISIBLE (3750 875);
FORCEADD Q_CAP_DIFFBUS..2
R 2
(3575 950);
FORCEPROP 1 LAST PART_NUMBER SP_CH4221MEE01
J 2
(3459 1038);
DISPLAY 0.574468 (3459 1038);
PAINT GREEN (3459 1038);
DISPLAY INVISIBLE (3459 1038);
FORCEPROP 2 LAST VALUE DIFF BUS_0.22UF
J 2
(3425 950);
DISPLAY 0.553191 (3425 950);
FORCEPROP 1 LAST $LOCATION C829
J 2
(3809 967);
DISPLAY 0.723404 (3809 967);
PAINT GREEN (3809 967);
FORCEPROP 2 LASTPIN (3650 950) $PN 1
J 0
(3660 960);
DISPLAY 0.808511 (3660 960);
FORCEPROP 2 LASTPIN (3500 950) $PN 2
J 2
(3490 960);
DISPLAY 0.808511 (3490 960);
FORCEPROP 1 LAST PIN_NAMES_ROTATE TRUE
J 2
(3575 950);
DISPLAY 0.489362 (3575 950);
PAINT GREEN (3575 950);
DISPLAY INVISIBLE (3575 950);
FORCEPROP 2 LAST CDS_LIB pure_quanta
J 2
(3575 950);
DISPLAY INVISIBLE (3575 950);
FORCEPROP 1 LAST CDS_LMAN_SYM_OUTLINE -25,50,25,-50
J 2
(3575 950);
DISPLAY 0.468085 (3575 950);
PAINT GREEN (3575 950);
DISPLAY INVISIBLE (3575 950);
FORCEPROP 2 LAST VOLTAGE 6.3V
J 2
(3225 1000);
DISPLAY 0.553191 (3225 1000);
DISPLAY INVISIBLE (3225 1000);
FORCEPROP 1 LAST MATERIAL X6S
J 2
(3584 1029);
DISPLAY 0.574468 (3584 1029);
PAINT GREEN (3584 1029);
DISPLAY INVISIBLE (3584 1029);
FORCEPROP 2 LAST PACK_TYPE C0201
J 2
(3400 1000);
DISPLAY 0.553191 (3400 1000);
DISPLAY INVISIBLE (3400 1000);
FORCEPROP 2 LAST TOLERANCE 20%
J 2
(3500 1000);
DISPLAY 0.553191 (3500 1000);
DISPLAY INVISIBLE (3500 1000);
FORCEPROP 1 LAST PATH I342
J 2
(3575 950);
DISPLAY 0.723404 (3575 950);
DISPLAY INVISIBLE (3575 950);
FORCEPROP 1 LAST $LOCATION C829
J 0
(3825 1025);
DISPLAY 1.021277 (3825 1025);
DISPLAY INVISIBLE (3825 1025);
FORCEPROP 2 LAST CDS_LOCATION C829
J 0
(3825 1025);
DISPLAY 1.021277 (3825 1025);
DISPLAY INVISIBLE (3825 1025);
FORCEPROP 2 LAST $SEC 1
J 2
(3750 1025);
DISPLAY 0.680851 (3750 1025);
PAINT MONO (3750 1025);
DISPLAY INVISIBLE (3750 1025);
FORCEPROP 2 LAST CDS_SEC 1
J 2
(3750 1025);
DISPLAY 0.680851 (3750 1025);
DISPLAY INVISIBLE (3750 1025);
FORCEADD Q_CAP_DIFFBUS..2
R 2
(3575 1150);
FORCEPROP 1 LAST PART_NUMBER SP_CH4221MEE01
J 2
(3459 1238);
DISPLAY 0.574468 (3459 1238);
PAINT GREEN (3459 1238);
DISPLAY INVISIBLE (3459 1238);
FORCEPROP 2 LAST VALUE DIFF BUS_0.22UF
J 2
(3425 1150);
DISPLAY 0.553191 (3425 1150);
FORCEPROP 1 LAST $LOCATION C827
J 2
(3809 1167);
DISPLAY 0.723404 (3809 1167);
PAINT GREEN (3809 1167);
FORCEPROP 2 LASTPIN (3650 1150) $PN 1
J 0
(3660 1160);
DISPLAY 0.808511 (3660 1160);
FORCEPROP 2 LASTPIN (3500 1150) $PN 2
J 2
(3490 1160);
DISPLAY 0.808511 (3490 1160);
FORCEPROP 1 LAST PIN_NAMES_ROTATE TRUE
J 2
(3575 1150);
DISPLAY 0.489362 (3575 1150);
PAINT GREEN (3575 1150);
DISPLAY INVISIBLE (3575 1150);
FORCEPROP 2 LAST CDS_LIB pure_quanta
J 2
(3575 1150);
DISPLAY INVISIBLE (3575 1150);
FORCEPROP 1 LAST CDS_LMAN_SYM_OUTLINE -25,50,25,-50
J 2
(3575 1150);
DISPLAY 0.468085 (3575 1150);
PAINT GREEN (3575 1150);
DISPLAY INVISIBLE (3575 1150);
FORCEPROP 2 LAST VOLTAGE 6.3V
J 2
(3225 1200);
DISPLAY 0.553191 (3225 1200);
DISPLAY INVISIBLE (3225 1200);
FORCEPROP 1 LAST MATERIAL X6S
J 2
(3584 1229);
DISPLAY 0.574468 (3584 1229);
PAINT GREEN (3584 1229);
DISPLAY INVISIBLE (3584 1229);
FORCEPROP 2 LAST PACK_TYPE C0201
J 2
(3400 1200);
DISPLAY 0.553191 (3400 1200);
DISPLAY INVISIBLE (3400 1200);
FORCEPROP 2 LAST TOLERANCE 20%
J 2
(3500 1200);
DISPLAY 0.553191 (3500 1200);
DISPLAY INVISIBLE (3500 1200);
FORCEPROP 1 LAST PATH I343
J 2
(3575 1150);
DISPLAY 0.723404 (3575 1150);
DISPLAY INVISIBLE (3575 1150);
FORCEPROP 1 LAST $LOCATION C827
J 0
(3825 1225);
DISPLAY 1.021277 (3825 1225);
DISPLAY INVISIBLE (3825 1225);
FORCEPROP 2 LAST CDS_LOCATION C827
J 0
(3825 1225);
DISPLAY 1.021277 (3825 1225);
DISPLAY INVISIBLE (3825 1225);
FORCEPROP 2 LAST $SEC 1
J 2
(3750 1225);
DISPLAY 0.680851 (3750 1225);
PAINT MONO (3750 1225);
DISPLAY INVISIBLE (3750 1225);
FORCEPROP 2 LAST CDS_SEC 1
J 2
(3750 1225);
DISPLAY 0.680851 (3750 1225);
DISPLAY INVISIBLE (3750 1225);
FORCEADD Q_CAP_DIFFBUS..2
R 2
(3575 1200);
FORCEPROP 1 LAST PART_NUMBER SP_CH4221MEE01
J 2
(3459 1288);
DISPLAY 0.574468 (3459 1288);
PAINT GREEN (3459 1288);
DISPLAY INVISIBLE (3459 1288);
FORCEPROP 2 LAST VALUE DIFF BUS_0.22UF
J 2
(3425 1200);
DISPLAY 0.553191 (3425 1200);
FORCEPROP 1 LAST $LOCATION C826
J 2
(3809 1217);
DISPLAY 0.723404 (3809 1217);
PAINT GREEN (3809 1217);
FORCEPROP 2 LASTPIN (3650 1200) $PN 1
J 0
(3660 1210);
DISPLAY 0.808511 (3660 1210);
FORCEPROP 2 LASTPIN (3500 1200) $PN 2
J 2
(3490 1210);
DISPLAY 0.808511 (3490 1210);
FORCEPROP 1 LAST PIN_NAMES_ROTATE TRUE
J 2
(3575 1200);
DISPLAY 0.489362 (3575 1200);
PAINT GREEN (3575 1200);
DISPLAY INVISIBLE (3575 1200);
FORCEPROP 2 LAST CDS_LIB pure_quanta
J 2
(3575 1200);
DISPLAY INVISIBLE (3575 1200);
FORCEPROP 1 LAST CDS_LMAN_SYM_OUTLINE -25,50,25,-50
J 2
(3575 1200);
DISPLAY 0.468085 (3575 1200);
PAINT GREEN (3575 1200);
DISPLAY INVISIBLE (3575 1200);
FORCEPROP 2 LAST VOLTAGE 6.3V
J 2
(3225 1250);
DISPLAY 0.553191 (3225 1250);
DISPLAY INVISIBLE (3225 1250);
FORCEPROP 1 LAST MATERIAL X6S
J 2
(3584 1279);
DISPLAY 0.574468 (3584 1279);
PAINT GREEN (3584 1279);
DISPLAY INVISIBLE (3584 1279);
FORCEPROP 2 LAST PACK_TYPE C0201
J 2
(3400 1250);
DISPLAY 0.553191 (3400 1250);
DISPLAY INVISIBLE (3400 1250);
FORCEPROP 2 LAST TOLERANCE 20%
J 2
(3500 1250);
DISPLAY 0.553191 (3500 1250);
DISPLAY INVISIBLE (3500 1250);
FORCEPROP 1 LAST PATH I344
J 2
(3575 1200);
DISPLAY 0.723404 (3575 1200);
DISPLAY INVISIBLE (3575 1200);
FORCEPROP 1 LAST $LOCATION C826
J 0
(3825 1275);
DISPLAY 1.021277 (3825 1275);
DISPLAY INVISIBLE (3825 1275);
FORCEPROP 2 LAST CDS_LOCATION C826
J 0
(3825 1275);
DISPLAY 1.021277 (3825 1275);
DISPLAY INVISIBLE (3825 1275);
FORCEPROP 2 LAST $SEC 1
J 2
(3750 1275);
DISPLAY 0.680851 (3750 1275);
PAINT MONO (3750 1275);
DISPLAY INVISIBLE (3750 1275);
FORCEPROP 2 LAST CDS_SEC 1
J 2
(3750 1275);
DISPLAY 0.680851 (3750 1275);
DISPLAY INVISIBLE (3750 1275);
FORCEADD Q_CAP_DIFFBUS..2
R 2
(3575 1600);
FORCEPROP 1 LAST PART_NUMBER SP_CH4221MEE01
J 2
(3459 1688);
DISPLAY 0.574468 (3459 1688);
PAINT GREEN (3459 1688);
DISPLAY INVISIBLE (3459 1688);
FORCEPROP 2 LAST VALUE DIFF BUS_0.22UF
J 2
(3425 1600);
DISPLAY 0.553191 (3425 1600);
FORCEPROP 1 LAST $LOCATION C822
J 2
(3809 1617);
DISPLAY 0.723404 (3809 1617);
PAINT GREEN (3809 1617);
FORCEPROP 2 LASTPIN (3650 1600) $PN 1
J 0
(3660 1610);
DISPLAY 0.808511 (3660 1610);
FORCEPROP 2 LASTPIN (3500 1600) $PN 2
J 2
(3490 1610);
DISPLAY 0.808511 (3490 1610);
FORCEPROP 1 LAST PIN_NAMES_ROTATE TRUE
J 2
(3575 1600);
DISPLAY 0.489362 (3575 1600);
PAINT GREEN (3575 1600);
DISPLAY INVISIBLE (3575 1600);
FORCEPROP 1 LAST CDS_LMAN_SYM_OUTLINE -25,50,25,-50
J 2
(3575 1600);
DISPLAY 0.468085 (3575 1600);
PAINT GREEN (3575 1600);
DISPLAY INVISIBLE (3575 1600);
FORCEPROP 2 LAST CDS_LIB pure_quanta
J 2
(3575 1600);
DISPLAY INVISIBLE (3575 1600);
FORCEPROP 2 LAST VOLTAGE 6.3V
J 2
(3225 1650);
DISPLAY 0.553191 (3225 1650);
DISPLAY INVISIBLE (3225 1650);
FORCEPROP 1 LAST MATERIAL X6S
J 2
(3584 1679);
DISPLAY 0.574468 (3584 1679);
PAINT GREEN (3584 1679);
DISPLAY INVISIBLE (3584 1679);
FORCEPROP 2 LAST PACK_TYPE C0201
J 2
(3400 1650);
DISPLAY 0.553191 (3400 1650);
DISPLAY INVISIBLE (3400 1650);
FORCEPROP 2 LAST TOLERANCE 20%
J 2
(3500 1650);
DISPLAY 0.553191 (3500 1650);
DISPLAY INVISIBLE (3500 1650);
FORCEPROP 1 LAST PATH I345
J 2
(3575 1600);
DISPLAY 0.723404 (3575 1600);
DISPLAY INVISIBLE (3575 1600);
FORCEPROP 1 LAST $LOCATION C822
J 0
(3825 1675);
DISPLAY 1.021277 (3825 1675);
DISPLAY INVISIBLE (3825 1675);
FORCEPROP 2 LAST CDS_LOCATION C822
J 0
(3825 1675);
DISPLAY 1.021277 (3825 1675);
DISPLAY INVISIBLE (3825 1675);
FORCEPROP 2 LAST $SEC 1
J 2
(3750 1675);
DISPLAY 0.680851 (3750 1675);
PAINT MONO (3750 1675);
DISPLAY INVISIBLE (3750 1675);
FORCEPROP 2 LAST CDS_SEC 1
J 2
(3750 1675);
DISPLAY 0.680851 (3750 1675);
DISPLAY INVISIBLE (3750 1675);
FORCEADD Q_CAP_DIFFBUS..2
R 2
(3575 1550);
FORCEPROP 1 LAST PART_NUMBER SP_CH4221MEE01
J 2
(3459 1638);
DISPLAY 0.574468 (3459 1638);
PAINT GREEN (3459 1638);
DISPLAY INVISIBLE (3459 1638);
FORCEPROP 2 LAST VALUE DIFF BUS_0.22UF
J 2
(3425 1550);
DISPLAY 0.553191 (3425 1550);
FORCEPROP 1 LAST $LOCATION C823
J 2
(3809 1567);
DISPLAY 0.723404 (3809 1567);
PAINT GREEN (3809 1567);
FORCEPROP 2 LASTPIN (3650 1550) $PN 1
J 0
(3660 1560);
DISPLAY 0.808511 (3660 1560);
FORCEPROP 2 LASTPIN (3500 1550) $PN 2
J 2
(3490 1560);
DISPLAY 0.808511 (3490 1560);
FORCEPROP 1 LAST PIN_NAMES_ROTATE TRUE
J 2
(3575 1550);
DISPLAY 0.489362 (3575 1550);
PAINT GREEN (3575 1550);
DISPLAY INVISIBLE (3575 1550);
FORCEPROP 2 LAST CDS_LIB pure_quanta
J 2
(3575 1550);
DISPLAY INVISIBLE (3575 1550);
FORCEPROP 1 LAST CDS_LMAN_SYM_OUTLINE -25,50,25,-50
J 2
(3575 1550);
DISPLAY 0.468085 (3575 1550);
PAINT GREEN (3575 1550);
DISPLAY INVISIBLE (3575 1550);
FORCEPROP 2 LAST VOLTAGE 6.3V
J 2
(3225 1600);
DISPLAY 0.553191 (3225 1600);
DISPLAY INVISIBLE (3225 1600);
FORCEPROP 1 LAST MATERIAL X6S
J 2
(3584 1629);
DISPLAY 0.574468 (3584 1629);
PAINT GREEN (3584 1629);
DISPLAY INVISIBLE (3584 1629);
FORCEPROP 2 LAST PACK_TYPE C0201
J 2
(3400 1600);
DISPLAY 0.553191 (3400 1600);
DISPLAY INVISIBLE (3400 1600);
FORCEPROP 2 LAST TOLERANCE 20%
J 2
(3500 1600);
DISPLAY 0.553191 (3500 1600);
DISPLAY INVISIBLE (3500 1600);
FORCEPROP 1 LAST PATH I346
J 2
(3575 1550);
DISPLAY 0.723404 (3575 1550);
DISPLAY INVISIBLE (3575 1550);
FORCEPROP 1 LAST $LOCATION C823
J 0
(3825 1625);
DISPLAY 1.021277 (3825 1625);
DISPLAY INVISIBLE (3825 1625);
FORCEPROP 2 LAST CDS_LOCATION C823
J 0
(3825 1625);
DISPLAY 1.021277 (3825 1625);
DISPLAY INVISIBLE (3825 1625);
FORCEPROP 2 LAST $SEC 1
J 2
(3750 1625);
DISPLAY 0.680851 (3750 1625);
PAINT MONO (3750 1625);
DISPLAY INVISIBLE (3750 1625);
FORCEPROP 2 LAST CDS_SEC 1
J 2
(3750 1625);
DISPLAY 0.680851 (3750 1625);
DISPLAY INVISIBLE (3750 1625);
FORCEADD TAP..1
R 2
(2600 2125);
FORCEPROP 3 LASTPIN (2650 2125) SIG_NAME P5E_CPU1_PE1_TX_DP<8>
J 0
(2660 2135);
DISPLAY 0.659574 (2660 2135);
PAINT MONO (2660 2135);
DISPLAY INVISIBLE (2660 2135);
FORCEPROP 1 LASTPIN (2650 2125) BN 8
J 2
(2662 2133);
DISPLAY 0.680851 (2662 2133);
PAINT GREEN (2662 2133);
FORCEPROP 2 LAST CDS_LIB standard
J 0
(2600 2125);
DISPLAY INVISIBLE (2600 2125);
FORCEPROP 1 LAST BODY_TYPE PLUMBING
J 2
(2600 2175);
DISPLAY 0.872340 (2600 2175);
PAINT GREEN (2600 2175);
DISPLAY INVISIBLE (2600 2175);
FORCEPROP 1 LAST HDL_TAP TRUE
J 2
(2275 2000);
DISPLAY 0.872340 (2275 2000);
DISPLAY INVISIBLE (2275 2000);
FORCEPROP 1 LAST PATH I347
J 2
(2602 2125);
DISPLAY 0.872340 (2602 2125);
PAINT GREEN (2602 2125);
DISPLAY INVISIBLE (2602 2125);
FORCEADD TAP..1
R 2
(2600 2325);
FORCEPROP 3 LASTPIN (2650 2325) SIG_NAME P5E_CPU1_PE1_TX_DP<9>
J 0
(2660 2335);
DISPLAY 0.659574 (2660 2335);
PAINT MONO (2660 2335);
DISPLAY INVISIBLE (2660 2335);
FORCEPROP 1 LASTPIN (2650 2325) BN 9
J 2
(2662 2333);
DISPLAY 0.680851 (2662 2333);
PAINT GREEN (2662 2333);
FORCEPROP 2 LAST CDS_LIB standard
J 0
(2600 2325);
DISPLAY INVISIBLE (2600 2325);
FORCEPROP 1 LAST BODY_TYPE PLUMBING
J 2
(2600 2375);
DISPLAY 0.872340 (2600 2375);
PAINT GREEN (2600 2375);
DISPLAY INVISIBLE (2600 2375);
FORCEPROP 1 LAST HDL_TAP TRUE
J 2
(2275 2200);
DISPLAY 0.872340 (2275 2200);
DISPLAY INVISIBLE (2275 2200);
FORCEPROP 1 LAST PATH I348
J 2
(2602 2325);
DISPLAY 0.872340 (2602 2325);
PAINT GREEN (2602 2325);
DISPLAY INVISIBLE (2602 2325);
FORCEADD TAP..1
R 2
(2600 2525);
FORCEPROP 3 LASTPIN (2650 2525) SIG_NAME P5E_CPU1_PE1_TX_DP<10>
J 0
(2660 2535);
DISPLAY 0.659574 (2660 2535);
PAINT MONO (2660 2535);
DISPLAY INVISIBLE (2660 2535);
FORCEPROP 1 LASTPIN (2650 2525) BN 10
J 2
(2662 2533);
DISPLAY 0.680851 (2662 2533);
PAINT GREEN (2662 2533);
FORCEPROP 2 LAST CDS_LIB standard
J 0
(2600 2525);
DISPLAY INVISIBLE (2600 2525);
FORCEPROP 1 LAST BODY_TYPE PLUMBING
J 2
(2600 2575);
DISPLAY 0.872340 (2600 2575);
PAINT GREEN (2600 2575);
DISPLAY INVISIBLE (2600 2575);
FORCEPROP 1 LAST HDL_TAP TRUE
J 2
(2275 2400);
DISPLAY 0.872340 (2275 2400);
DISPLAY INVISIBLE (2275 2400);
FORCEPROP 1 LAST PATH I349
J 2
(2602 2525);
DISPLAY 0.872340 (2602 2525);
PAINT GREEN (2602 2525);
DISPLAY INVISIBLE (2602 2525);
FORCEADD TAP..1
R 2
(2850 2175);
FORCEPROP 3 LASTPIN (2900 2175) SIG_NAME P5E_CPU1_PE1_TX_DN<8>
J 0
(2910 2185);
DISPLAY 0.659574 (2910 2185);
PAINT MONO (2910 2185);
DISPLAY INVISIBLE (2910 2185);
FORCEPROP 1 LASTPIN (2900 2175) BN 8
J 2
(2912 2183);
DISPLAY 0.680851 (2912 2183);
PAINT GREEN (2912 2183);
FORCEPROP 2 LAST CDS_LIB standard
J 0
(2850 2175);
DISPLAY INVISIBLE (2850 2175);
FORCEPROP 1 LAST BODY_TYPE PLUMBING
J 2
(2850 2225);
DISPLAY 0.872340 (2850 2225);
PAINT GREEN (2850 2225);
DISPLAY INVISIBLE (2850 2225);
FORCEPROP 1 LAST HDL_TAP TRUE
J 2
(2525 2050);
DISPLAY 0.872340 (2525 2050);
DISPLAY INVISIBLE (2525 2050);
FORCEPROP 1 LAST PATH I350
J 2
(2852 2175);
DISPLAY 0.872340 (2852 2175);
PAINT GREEN (2852 2175);
DISPLAY INVISIBLE (2852 2175);
FORCEADD TAP..1
R 2
(2850 2375);
FORCEPROP 3 LASTPIN (2900 2375) SIG_NAME P5E_CPU1_PE1_TX_DN<9>
J 0
(2910 2385);
DISPLAY 0.659574 (2910 2385);
PAINT MONO (2910 2385);
DISPLAY INVISIBLE (2910 2385);
FORCEPROP 1 LASTPIN (2900 2375) BN 9
J 2
(2912 2383);
DISPLAY 0.680851 (2912 2383);
PAINT GREEN (2912 2383);
FORCEPROP 2 LAST CDS_LIB standard
J 0
(2850 2375);
DISPLAY INVISIBLE (2850 2375);
FORCEPROP 1 LAST BODY_TYPE PLUMBING
J 2
(2850 2425);
DISPLAY 0.872340 (2850 2425);
PAINT GREEN (2850 2425);
DISPLAY INVISIBLE (2850 2425);
FORCEPROP 1 LAST HDL_TAP TRUE
J 2
(2525 2250);
DISPLAY 0.872340 (2525 2250);
DISPLAY INVISIBLE (2525 2250);
FORCEPROP 1 LAST PATH I351
J 2
(2852 2375);
DISPLAY 0.872340 (2852 2375);
PAINT GREEN (2852 2375);
DISPLAY INVISIBLE (2852 2375);
FORCEADD TAP..1
R 2
(2600 2725);
FORCEPROP 3 LASTPIN (2650 2725) SIG_NAME P5E_CPU1_PE1_TX_DP<11>
J 0
(2660 2735);
DISPLAY 0.659574 (2660 2735);
PAINT MONO (2660 2735);
DISPLAY INVISIBLE (2660 2735);
FORCEPROP 1 LASTPIN (2650 2725) BN 11
J 2
(2662 2733);
DISPLAY 0.680851 (2662 2733);
PAINT GREEN (2662 2733);
FORCEPROP 2 LAST CDS_LIB standard
J 0
(2600 2725);
DISPLAY INVISIBLE (2600 2725);
FORCEPROP 1 LAST BODY_TYPE PLUMBING
J 2
(2600 2775);
DISPLAY 0.872340 (2600 2775);
PAINT GREEN (2600 2775);
DISPLAY INVISIBLE (2600 2775);
FORCEPROP 1 LAST HDL_TAP TRUE
J 2
(2275 2600);
DISPLAY 0.872340 (2275 2600);
DISPLAY INVISIBLE (2275 2600);
FORCEPROP 1 LAST PATH I352
J 2
(2602 2725);
DISPLAY 0.872340 (2602 2725);
PAINT GREEN (2602 2725);
DISPLAY INVISIBLE (2602 2725);
FORCEADD TAP..1
R 2
(2600 2925);
FORCEPROP 3 LASTPIN (2650 2925) SIG_NAME P5E_CPU1_PE1_TX_DP<12>
J 0
(2660 2935);
DISPLAY 0.659574 (2660 2935);
PAINT MONO (2660 2935);
DISPLAY INVISIBLE (2660 2935);
FORCEPROP 1 LASTPIN (2650 2925) BN 12
J 2
(2662 2933);
DISPLAY 0.680851 (2662 2933);
PAINT GREEN (2662 2933);
FORCEPROP 2 LAST CDS_LIB standard
J 0
(2600 2925);
DISPLAY INVISIBLE (2600 2925);
FORCEPROP 1 LAST BODY_TYPE PLUMBING
J 2
(2600 2975);
DISPLAY 0.872340 (2600 2975);
PAINT GREEN (2600 2975);
DISPLAY INVISIBLE (2600 2975);
FORCEPROP 1 LAST HDL_TAP TRUE
J 2
(2275 2800);
DISPLAY 0.872340 (2275 2800);
DISPLAY INVISIBLE (2275 2800);
FORCEPROP 1 LAST PATH I353
J 2
(2602 2925);
DISPLAY 0.872340 (2602 2925);
PAINT GREEN (2602 2925);
DISPLAY INVISIBLE (2602 2925);
FORCEADD TAP..1
R 2
(2850 2575);
FORCEPROP 3 LASTPIN (2900 2575) SIG_NAME P5E_CPU1_PE1_TX_DN<10>
J 0
(2910 2585);
DISPLAY 0.659574 (2910 2585);
PAINT MONO (2910 2585);
DISPLAY INVISIBLE (2910 2585);
FORCEPROP 1 LASTPIN (2900 2575) BN 10
J 2
(2912 2583);
DISPLAY 0.680851 (2912 2583);
PAINT GREEN (2912 2583);
FORCEPROP 2 LAST CDS_LIB standard
J 0
(2850 2575);
DISPLAY INVISIBLE (2850 2575);
FORCEPROP 1 LAST BODY_TYPE PLUMBING
J 2
(2850 2625);
DISPLAY 0.872340 (2850 2625);
PAINT GREEN (2850 2625);
DISPLAY INVISIBLE (2850 2625);
FORCEPROP 1 LAST HDL_TAP TRUE
J 2
(2525 2450);
DISPLAY 0.872340 (2525 2450);
DISPLAY INVISIBLE (2525 2450);
FORCEPROP 1 LAST PATH I354
J 2
(2852 2575);
DISPLAY 0.872340 (2852 2575);
PAINT GREEN (2852 2575);
DISPLAY INVISIBLE (2852 2575);
FORCEADD TAP..1
R 2
(2850 2775);
FORCEPROP 3 LASTPIN (2900 2775) SIG_NAME P5E_CPU1_PE1_TX_DN<11>
J 0
(2910 2785);
DISPLAY 0.659574 (2910 2785);
PAINT MONO (2910 2785);
DISPLAY INVISIBLE (2910 2785);
FORCEPROP 1 LASTPIN (2900 2775) BN 11
J 2
(2912 2783);
DISPLAY 0.680851 (2912 2783);
PAINT GREEN (2912 2783);
FORCEPROP 2 LAST CDS_LIB standard
J 0
(2850 2775);
DISPLAY INVISIBLE (2850 2775);
FORCEPROP 1 LAST BODY_TYPE PLUMBING
J 2
(2850 2825);
DISPLAY 0.872340 (2850 2825);
PAINT GREEN (2850 2825);
DISPLAY INVISIBLE (2850 2825);
FORCEPROP 1 LAST HDL_TAP TRUE
J 2
(2525 2650);
DISPLAY 0.872340 (2525 2650);
DISPLAY INVISIBLE (2525 2650);
FORCEPROP 1 LAST PATH I355
J 2
(2852 2775);
DISPLAY 0.872340 (2852 2775);
PAINT GREEN (2852 2775);
DISPLAY INVISIBLE (2852 2775);
FORCEADD TAP..1
R 2
(2850 2975);
FORCEPROP 3 LASTPIN (2900 2975) SIG_NAME P5E_CPU1_PE1_TX_DN<12>
J 0
(2910 2985);
DISPLAY 0.659574 (2910 2985);
PAINT MONO (2910 2985);
DISPLAY INVISIBLE (2910 2985);
FORCEPROP 1 LASTPIN (2900 2975) BN 12
J 2
(2912 2983);
DISPLAY 0.680851 (2912 2983);
PAINT GREEN (2912 2983);
FORCEPROP 2 LAST CDS_LIB standard
J 0
(2850 2975);
DISPLAY INVISIBLE (2850 2975);
FORCEPROP 1 LAST BODY_TYPE PLUMBING
J 2
(2850 3025);
DISPLAY 0.872340 (2850 3025);
PAINT GREEN (2850 3025);
DISPLAY INVISIBLE (2850 3025);
FORCEPROP 1 LAST HDL_TAP TRUE
J 2
(2525 2850);
DISPLAY 0.872340 (2525 2850);
DISPLAY INVISIBLE (2525 2850);
FORCEPROP 1 LAST PATH I356
J 2
(2852 2975);
DISPLAY 0.872340 (2852 2975);
PAINT GREEN (2852 2975);
DISPLAY INVISIBLE (2852 2975);
FORCEADD TAP..1
R 2
(2600 3125);
FORCEPROP 3 LASTPIN (2650 3125) SIG_NAME P5E_CPU1_PE1_TX_DP<13>
J 0
(2660 3135);
DISPLAY 0.659574 (2660 3135);
PAINT MONO (2660 3135);
DISPLAY INVISIBLE (2660 3135);
FORCEPROP 1 LASTPIN (2650 3125) BN 13
J 2
(2662 3133);
DISPLAY 0.680851 (2662 3133);
PAINT GREEN (2662 3133);
FORCEPROP 2 LAST CDS_LIB standard
J 0
(2600 3125);
DISPLAY INVISIBLE (2600 3125);
FORCEPROP 1 LAST BODY_TYPE PLUMBING
J 2
(2600 3175);
DISPLAY 0.872340 (2600 3175);
PAINT GREEN (2600 3175);
DISPLAY INVISIBLE (2600 3175);
FORCEPROP 1 LAST HDL_TAP TRUE
J 2
(2275 3000);
DISPLAY 0.872340 (2275 3000);
DISPLAY INVISIBLE (2275 3000);
FORCEPROP 1 LAST PATH I357
J 2
(2602 3125);
DISPLAY 0.872340 (2602 3125);
PAINT GREEN (2602 3125);
DISPLAY INVISIBLE (2602 3125);
FORCEADD TAP..1
R 2
(2600 3325);
FORCEPROP 3 LASTPIN (2650 3325) SIG_NAME P5E_CPU1_PE1_TX_DP<14>
J 0
(2660 3335);
DISPLAY 0.659574 (2660 3335);
PAINT MONO (2660 3335);
DISPLAY INVISIBLE (2660 3335);
FORCEPROP 1 LASTPIN (2650 3325) BN 14
J 2
(2662 3333);
DISPLAY 0.680851 (2662 3333);
PAINT GREEN (2662 3333);
FORCEPROP 2 LAST CDS_LIB standard
J 0
(2600 3325);
DISPLAY INVISIBLE (2600 3325);
FORCEPROP 1 LAST BODY_TYPE PLUMBING
J 2
(2600 3375);
DISPLAY 0.872340 (2600 3375);
PAINT GREEN (2600 3375);
DISPLAY INVISIBLE (2600 3375);
FORCEPROP 1 LAST HDL_TAP TRUE
J 2
(2275 3200);
DISPLAY 0.872340 (2275 3200);
DISPLAY INVISIBLE (2275 3200);
FORCEPROP 1 LAST PATH I358
J 2
(2602 3325);
DISPLAY 0.872340 (2602 3325);
PAINT GREEN (2602 3325);
DISPLAY INVISIBLE (2602 3325);
FORCEADD TAP..1
R 2
(2600 3525);
FORCEPROP 3 LASTPIN (2650 3525) SIG_NAME P5E_CPU1_PE1_TX_DP<15>
J 0
(2660 3535);
DISPLAY 0.659574 (2660 3535);
PAINT MONO (2660 3535);
DISPLAY INVISIBLE (2660 3535);
FORCEPROP 1 LASTPIN (2650 3525) BN 15
J 2
(2662 3533);
DISPLAY 0.680851 (2662 3533);
PAINT GREEN (2662 3533);
FORCEPROP 2 LAST CDS_LIB standard
J 0
(2600 3525);
DISPLAY INVISIBLE (2600 3525);
FORCEPROP 1 LAST BODY_TYPE PLUMBING
J 2
(2600 3575);
DISPLAY 0.872340 (2600 3575);
PAINT GREEN (2600 3575);
DISPLAY INVISIBLE (2600 3575);
FORCEPROP 1 LAST HDL_TAP TRUE
J 2
(2275 3400);
DISPLAY 0.872340 (2275 3400);
DISPLAY INVISIBLE (2275 3400);
FORCEPROP 1 LAST PATH I359
J 2
(2602 3525);
DISPLAY 0.872340 (2602 3525);
PAINT GREEN (2602 3525);
DISPLAY INVISIBLE (2602 3525);
FORCEADD TAP..1
R 2
(2850 3175);
FORCEPROP 3 LASTPIN (2900 3175) SIG_NAME P5E_CPU1_PE1_TX_DN<13>
J 0
(2910 3185);
DISPLAY 0.659574 (2910 3185);
PAINT MONO (2910 3185);
DISPLAY INVISIBLE (2910 3185);
FORCEPROP 1 LASTPIN (2900 3175) BN 13
J 2
(2912 3183);
DISPLAY 0.680851 (2912 3183);
PAINT GREEN (2912 3183);
FORCEPROP 2 LAST CDS_LIB standard
J 0
(2850 3175);
DISPLAY INVISIBLE (2850 3175);
FORCEPROP 1 LAST BODY_TYPE PLUMBING
J 2
(2850 3225);
DISPLAY 0.872340 (2850 3225);
PAINT GREEN (2850 3225);
DISPLAY INVISIBLE (2850 3225);
FORCEPROP 1 LAST HDL_TAP TRUE
J 2
(2525 3050);
DISPLAY 0.872340 (2525 3050);
DISPLAY INVISIBLE (2525 3050);
FORCEPROP 1 LAST PATH I360
J 2
(2852 3175);
DISPLAY 0.872340 (2852 3175);
PAINT GREEN (2852 3175);
DISPLAY INVISIBLE (2852 3175);
FORCEADD TAP..1
R 2
(2850 3375);
FORCEPROP 3 LASTPIN (2900 3375) SIG_NAME P5E_CPU1_PE1_TX_DN<14>
J 0
(2910 3385);
DISPLAY 0.659574 (2910 3385);
PAINT MONO (2910 3385);
DISPLAY INVISIBLE (2910 3385);
FORCEPROP 1 LASTPIN (2900 3375) BN 14
J 2
(2912 3383);
DISPLAY 0.680851 (2912 3383);
PAINT GREEN (2912 3383);
FORCEPROP 2 LAST CDS_LIB standard
J 0
(2850 3375);
DISPLAY INVISIBLE (2850 3375);
FORCEPROP 1 LAST BODY_TYPE PLUMBING
J 2
(2850 3425);
DISPLAY 0.872340 (2850 3425);
PAINT GREEN (2850 3425);
DISPLAY INVISIBLE (2850 3425);
FORCEPROP 1 LAST HDL_TAP TRUE
J 2
(2525 3250);
DISPLAY 0.872340 (2525 3250);
DISPLAY INVISIBLE (2525 3250);
FORCEPROP 1 LAST PATH I361
J 2
(2852 3375);
DISPLAY 0.872340 (2852 3375);
PAINT GREEN (2852 3375);
DISPLAY INVISIBLE (2852 3375);
FORCEADD TAP..1
R 2
(2850 3575);
FORCEPROP 3 LASTPIN (2900 3575) SIG_NAME P5E_CPU1_PE1_TX_DN<15>
J 0
(2910 3585);
DISPLAY 0.659574 (2910 3585);
PAINT MONO (2910 3585);
DISPLAY INVISIBLE (2910 3585);
FORCEPROP 1 LASTPIN (2900 3575) BN 15
J 2
(2912 3583);
DISPLAY 0.680851 (2912 3583);
PAINT GREEN (2912 3583);
FORCEPROP 2 LAST CDS_LIB standard
J 0
(2850 3575);
DISPLAY INVISIBLE (2850 3575);
FORCEPROP 1 LAST BODY_TYPE PLUMBING
J 2
(2850 3625);
DISPLAY 0.872340 (2850 3625);
PAINT GREEN (2850 3625);
DISPLAY INVISIBLE (2850 3625);
FORCEPROP 1 LAST HDL_TAP TRUE
J 2
(2525 3450);
DISPLAY 0.872340 (2525 3450);
DISPLAY INVISIBLE (2525 3450);
FORCEPROP 1 LAST PATH I362
J 2
(2852 3575);
DISPLAY 0.872340 (2852 3575);
PAINT GREEN (2852 3575);
DISPLAY INVISIBLE (2852 3575);
FORCEADD Q_CAP_DIFFBUS..2
R 2
(3575 2175);
FORCEPROP 1 LAST PART_NUMBER SP_CH4221MEE01
J 2
(3459 2263);
DISPLAY 0.574468 (3459 2263);
PAINT GREEN (3459 2263);
DISPLAY INVISIBLE (3459 2263);
FORCEPROP 2 LAST VALUE DIFF BUS_0.22UF
J 2
(3425 2175);
DISPLAY 0.553191 (3425 2175);
FORCEPROP 1 LAST $LOCATION C820
J 2
(3809 2192);
DISPLAY 0.723404 (3809 2192);
PAINT GREEN (3809 2192);
FORCEPROP 2 LASTPIN (3650 2175) $PN 1
J 0
(3660 2185);
DISPLAY 0.808511 (3660 2185);
FORCEPROP 2 LASTPIN (3500 2175) $PN 2
J 2
(3490 2185);
DISPLAY 0.808511 (3490 2185);
FORCEPROP 1 LAST CDS_LMAN_SYM_OUTLINE -25,50,25,-50
J 2
(3575 2175);
DISPLAY 0.468085 (3575 2175);
PAINT GREEN (3575 2175);
DISPLAY INVISIBLE (3575 2175);
FORCEPROP 2 LAST CDS_LIB pure_quanta
J 2
(3575 2175);
DISPLAY INVISIBLE (3575 2175);
FORCEPROP 1 LAST PIN_NAMES_ROTATE TRUE
J 2
(3575 2175);
DISPLAY 0.489362 (3575 2175);
PAINT GREEN (3575 2175);
DISPLAY INVISIBLE (3575 2175);
FORCEPROP 2 LAST VOLTAGE 6.3V
J 2
(3225 2225);
DISPLAY 0.553191 (3225 2225);
DISPLAY INVISIBLE (3225 2225);
FORCEPROP 1 LAST MATERIAL X6S
J 2
(3584 2254);
DISPLAY 0.574468 (3584 2254);
PAINT GREEN (3584 2254);
DISPLAY INVISIBLE (3584 2254);
FORCEPROP 2 LAST PACK_TYPE C0201
J 2
(3400 2225);
DISPLAY 0.553191 (3400 2225);
DISPLAY INVISIBLE (3400 2225);
FORCEPROP 2 LAST TOLERANCE 20%
J 2
(3500 2225);
DISPLAY 0.553191 (3500 2225);
DISPLAY INVISIBLE (3500 2225);
FORCEPROP 1 LAST PATH I363
J 2
(3575 2175);
DISPLAY 0.723404 (3575 2175);
DISPLAY INVISIBLE (3575 2175);
FORCEPROP 1 LAST $LOCATION C820
J 0
(3825 2250);
DISPLAY 1.021277 (3825 2250);
DISPLAY INVISIBLE (3825 2250);
FORCEPROP 2 LAST CDS_LOCATION C820
J 0
(3825 2250);
DISPLAY 1.021277 (3825 2250);
DISPLAY INVISIBLE (3825 2250);
FORCEPROP 2 LAST $SEC 1
J 2
(3750 2250);
DISPLAY 0.680851 (3750 2250);
PAINT MONO (3750 2250);
DISPLAY INVISIBLE (3750 2250);
FORCEPROP 2 LAST CDS_SEC 1
J 2
(3750 2250);
DISPLAY 0.680851 (3750 2250);
DISPLAY INVISIBLE (3750 2250);
FORCEADD Q_CAP_DIFFBUS..2
R 2
(3575 2125);
FORCEPROP 1 LAST PART_NUMBER SP_CH4221MEE01
J 2
(3459 2213);
DISPLAY 0.574468 (3459 2213);
PAINT GREEN (3459 2213);
DISPLAY INVISIBLE (3459 2213);
FORCEPROP 2 LAST VALUE DIFF BUS_0.22UF
J 2
(3425 2125);
DISPLAY 0.553191 (3425 2125);
FORCEPROP 1 LAST $LOCATION C821
J 2
(3809 2142);
DISPLAY 0.723404 (3809 2142);
PAINT GREEN (3809 2142);
FORCEPROP 2 LASTPIN (3650 2125) $PN 1
J 0
(3660 2135);
DISPLAY 0.808511 (3660 2135);
FORCEPROP 2 LASTPIN (3500 2125) $PN 2
J 2
(3490 2135);
DISPLAY 0.808511 (3490 2135);
FORCEPROP 1 LAST CDS_LMAN_SYM_OUTLINE -25,50,25,-50
J 2
(3575 2125);
DISPLAY 0.468085 (3575 2125);
PAINT GREEN (3575 2125);
DISPLAY INVISIBLE (3575 2125);
FORCEPROP 2 LAST CDS_LIB pure_quanta
J 2
(3575 2125);
DISPLAY INVISIBLE (3575 2125);
FORCEPROP 1 LAST PIN_NAMES_ROTATE TRUE
J 2
(3575 2125);
DISPLAY 0.489362 (3575 2125);
PAINT GREEN (3575 2125);
DISPLAY INVISIBLE (3575 2125);
FORCEPROP 2 LAST VOLTAGE 6.3V
J 2
(3225 2175);
DISPLAY 0.553191 (3225 2175);
DISPLAY INVISIBLE (3225 2175);
FORCEPROP 1 LAST MATERIAL X6S
J 2
(3584 2204);
DISPLAY 0.574468 (3584 2204);
PAINT GREEN (3584 2204);
DISPLAY INVISIBLE (3584 2204);
FORCEPROP 2 LAST PACK_TYPE C0201
J 2
(3400 2175);
DISPLAY 0.553191 (3400 2175);
DISPLAY INVISIBLE (3400 2175);
FORCEPROP 2 LAST TOLERANCE 20%
J 2
(3500 2175);
DISPLAY 0.553191 (3500 2175);
DISPLAY INVISIBLE (3500 2175);
FORCEPROP 1 LAST PATH I364
J 2
(3575 2125);
DISPLAY 0.723404 (3575 2125);
DISPLAY INVISIBLE (3575 2125);
FORCEPROP 1 LAST $LOCATION C821
J 0
(3825 2200);
DISPLAY 1.021277 (3825 2200);
DISPLAY INVISIBLE (3825 2200);
FORCEPROP 2 LAST CDS_LOCATION C821
J 0
(3825 2200);
DISPLAY 1.021277 (3825 2200);
DISPLAY INVISIBLE (3825 2200);
FORCEPROP 2 LAST $SEC 1
J 2
(3750 2200);
DISPLAY 0.680851 (3750 2200);
PAINT MONO (3750 2200);
DISPLAY INVISIBLE (3750 2200);
FORCEPROP 2 LAST CDS_SEC 1
J 2
(3750 2200);
DISPLAY 0.680851 (3750 2200);
DISPLAY INVISIBLE (3750 2200);
FORCEADD Q_CAP_DIFFBUS..2
R 2
(3575 2375);
FORCEPROP 1 LAST PART_NUMBER SP_CH4221MEE01
J 2
(3459 2463);
DISPLAY 0.574468 (3459 2463);
PAINT GREEN (3459 2463);
DISPLAY INVISIBLE (3459 2463);
FORCEPROP 2 LAST VALUE DIFF BUS_0.22UF
J 2
(3425 2375);
DISPLAY 0.553191 (3425 2375);
FORCEPROP 1 LAST $LOCATION C818
J 2
(3809 2392);
DISPLAY 0.723404 (3809 2392);
PAINT GREEN (3809 2392);
FORCEPROP 2 LASTPIN (3650 2375) $PN 1
J 0
(3660 2385);
DISPLAY 0.808511 (3660 2385);
FORCEPROP 2 LASTPIN (3500 2375) $PN 2
J 2
(3490 2385);
DISPLAY 0.808511 (3490 2385);
FORCEPROP 2 LAST CDS_LIB pure_quanta
J 2
(3575 2375);
DISPLAY INVISIBLE (3575 2375);
FORCEPROP 1 LAST CDS_LMAN_SYM_OUTLINE -25,50,25,-50
J 2
(3575 2375);
DISPLAY 0.468085 (3575 2375);
PAINT GREEN (3575 2375);
DISPLAY INVISIBLE (3575 2375);
FORCEPROP 1 LAST PIN_NAMES_ROTATE TRUE
J 2
(3575 2375);
DISPLAY 0.489362 (3575 2375);
PAINT GREEN (3575 2375);
DISPLAY INVISIBLE (3575 2375);
FORCEPROP 2 LAST VOLTAGE 6.3V
J 2
(3225 2425);
DISPLAY 0.553191 (3225 2425);
DISPLAY INVISIBLE (3225 2425);
FORCEPROP 1 LAST MATERIAL X6S
J 2
(3584 2454);
DISPLAY 0.574468 (3584 2454);
PAINT GREEN (3584 2454);
DISPLAY INVISIBLE (3584 2454);
FORCEPROP 2 LAST PACK_TYPE C0201
J 2
(3400 2425);
DISPLAY 0.553191 (3400 2425);
DISPLAY INVISIBLE (3400 2425);
FORCEPROP 2 LAST TOLERANCE 20%
J 2
(3500 2425);
DISPLAY 0.553191 (3500 2425);
DISPLAY INVISIBLE (3500 2425);
FORCEPROP 1 LAST PATH I365
J 2
(3575 2375);
DISPLAY 0.723404 (3575 2375);
DISPLAY INVISIBLE (3575 2375);
FORCEPROP 1 LAST $LOCATION C818
J 0
(3825 2450);
DISPLAY 1.021277 (3825 2450);
DISPLAY INVISIBLE (3825 2450);
FORCEPROP 2 LAST CDS_LOCATION C818
J 0
(3825 2450);
DISPLAY 1.021277 (3825 2450);
DISPLAY INVISIBLE (3825 2450);
FORCEPROP 2 LAST $SEC 1
J 2
(3750 2450);
DISPLAY 0.680851 (3750 2450);
PAINT MONO (3750 2450);
DISPLAY INVISIBLE (3750 2450);
FORCEPROP 2 LAST CDS_SEC 1
J 2
(3750 2450);
DISPLAY 0.680851 (3750 2450);
DISPLAY INVISIBLE (3750 2450);
FORCEADD Q_CAP_DIFFBUS..2
R 2
(3575 2325);
FORCEPROP 1 LAST PART_NUMBER SP_CH4221MEE01
J 2
(3459 2413);
DISPLAY 0.574468 (3459 2413);
PAINT GREEN (3459 2413);
DISPLAY INVISIBLE (3459 2413);
FORCEPROP 2 LAST VALUE DIFF BUS_0.22UF
J 2
(3425 2325);
DISPLAY 0.553191 (3425 2325);
FORCEPROP 1 LAST $LOCATION C819
J 2
(3809 2342);
DISPLAY 0.723404 (3809 2342);
PAINT GREEN (3809 2342);
FORCEPROP 2 LASTPIN (3650 2325) $PN 1
J 0
(3660 2335);
DISPLAY 0.808511 (3660 2335);
FORCEPROP 2 LASTPIN (3500 2325) $PN 2
J 2
(3490 2335);
DISPLAY 0.808511 (3490 2335);
FORCEPROP 1 LAST CDS_LMAN_SYM_OUTLINE -25,50,25,-50
J 2
(3575 2325);
DISPLAY 0.468085 (3575 2325);
PAINT GREEN (3575 2325);
DISPLAY INVISIBLE (3575 2325);
FORCEPROP 2 LAST CDS_LIB pure_quanta
J 2
(3575 2325);
DISPLAY INVISIBLE (3575 2325);
FORCEPROP 1 LAST PIN_NAMES_ROTATE TRUE
J 2
(3575 2325);
DISPLAY 0.489362 (3575 2325);
PAINT GREEN (3575 2325);
DISPLAY INVISIBLE (3575 2325);
FORCEPROP 2 LAST VOLTAGE 6.3V
J 2
(3225 2375);
DISPLAY 0.553191 (3225 2375);
DISPLAY INVISIBLE (3225 2375);
FORCEPROP 1 LAST MATERIAL X6S
J 2
(3584 2404);
DISPLAY 0.574468 (3584 2404);
PAINT GREEN (3584 2404);
DISPLAY INVISIBLE (3584 2404);
FORCEPROP 2 LAST PACK_TYPE C0201
J 2
(3400 2375);
DISPLAY 0.553191 (3400 2375);
DISPLAY INVISIBLE (3400 2375);
FORCEPROP 2 LAST TOLERANCE 20%
J 2
(3500 2375);
DISPLAY 0.553191 (3500 2375);
DISPLAY INVISIBLE (3500 2375);
FORCEPROP 1 LAST PATH I366
J 2
(3575 2325);
DISPLAY 0.723404 (3575 2325);
DISPLAY INVISIBLE (3575 2325);
FORCEPROP 1 LAST $LOCATION C819
J 0
(3825 2400);
DISPLAY 1.021277 (3825 2400);
DISPLAY INVISIBLE (3825 2400);
FORCEPROP 2 LAST CDS_LOCATION C819
J 0
(3825 2400);
DISPLAY 1.021277 (3825 2400);
DISPLAY INVISIBLE (3825 2400);
FORCEPROP 2 LAST $SEC 1
J 2
(3750 2400);
DISPLAY 0.680851 (3750 2400);
PAINT MONO (3750 2400);
DISPLAY INVISIBLE (3750 2400);
FORCEPROP 2 LAST CDS_SEC 1
J 2
(3750 2400);
DISPLAY 0.680851 (3750 2400);
DISPLAY INVISIBLE (3750 2400);
FORCEADD Q_CAP_DIFFBUS..2
R 2
(3575 2525);
FORCEPROP 1 LAST PART_NUMBER SP_CH4221MEE01
J 2
(3459 2613);
DISPLAY 0.574468 (3459 2613);
PAINT GREEN (3459 2613);
DISPLAY INVISIBLE (3459 2613);
FORCEPROP 2 LAST VALUE DIFF BUS_0.22UF
J 2
(3425 2525);
DISPLAY 0.553191 (3425 2525);
FORCEPROP 1 LAST $LOCATION C817
J 2
(3809 2542);
DISPLAY 0.723404 (3809 2542);
PAINT GREEN (3809 2542);
FORCEPROP 2 LASTPIN (3650 2525) $PN 1
J 0
(3660 2535);
DISPLAY 0.808511 (3660 2535);
FORCEPROP 2 LASTPIN (3500 2525) $PN 2
J 2
(3490 2535);
DISPLAY 0.808511 (3490 2535);
FORCEPROP 1 LAST CDS_LMAN_SYM_OUTLINE -25,50,25,-50
J 2
(3575 2525);
DISPLAY 0.468085 (3575 2525);
PAINT GREEN (3575 2525);
DISPLAY INVISIBLE (3575 2525);
FORCEPROP 2 LAST CDS_LIB pure_quanta
J 2
(3575 2525);
DISPLAY INVISIBLE (3575 2525);
FORCEPROP 1 LAST PIN_NAMES_ROTATE TRUE
J 2
(3575 2525);
DISPLAY 0.489362 (3575 2525);
PAINT GREEN (3575 2525);
DISPLAY INVISIBLE (3575 2525);
FORCEPROP 2 LAST VOLTAGE 6.3V
J 2
(3225 2575);
DISPLAY 0.553191 (3225 2575);
DISPLAY INVISIBLE (3225 2575);
FORCEPROP 1 LAST MATERIAL X6S
J 2
(3584 2604);
DISPLAY 0.574468 (3584 2604);
PAINT GREEN (3584 2604);
DISPLAY INVISIBLE (3584 2604);
FORCEPROP 2 LAST PACK_TYPE C0201
J 2
(3400 2575);
DISPLAY 0.553191 (3400 2575);
DISPLAY INVISIBLE (3400 2575);
FORCEPROP 2 LAST TOLERANCE 20%
J 2
(3500 2575);
DISPLAY 0.553191 (3500 2575);
DISPLAY INVISIBLE (3500 2575);
FORCEPROP 1 LAST PATH I367
J 2
(3575 2525);
DISPLAY 0.723404 (3575 2525);
DISPLAY INVISIBLE (3575 2525);
FORCEPROP 1 LAST $LOCATION C817
J 0
(3825 2600);
DISPLAY 1.021277 (3825 2600);
DISPLAY INVISIBLE (3825 2600);
FORCEPROP 2 LAST CDS_LOCATION C817
J 0
(3825 2600);
DISPLAY 1.021277 (3825 2600);
DISPLAY INVISIBLE (3825 2600);
FORCEPROP 2 LAST $SEC 1
J 2
(3750 2600);
DISPLAY 0.680851 (3750 2600);
PAINT MONO (3750 2600);
DISPLAY INVISIBLE (3750 2600);
FORCEPROP 2 LAST CDS_SEC 1
J 2
(3750 2600);
DISPLAY 0.680851 (3750 2600);
DISPLAY INVISIBLE (3750 2600);
FORCEADD Q_CAP_DIFFBUS..2
R 2
(3575 2575);
FORCEPROP 1 LAST PART_NUMBER SP_CH4221MEE01
J 2
(3459 2663);
DISPLAY 0.574468 (3459 2663);
PAINT GREEN (3459 2663);
DISPLAY INVISIBLE (3459 2663);
FORCEPROP 2 LAST VALUE DIFF BUS_0.22UF
J 2
(3425 2575);
DISPLAY 0.553191 (3425 2575);
FORCEPROP 1 LAST $LOCATION C816
J 2
(3809 2592);
DISPLAY 0.723404 (3809 2592);
PAINT GREEN (3809 2592);
FORCEPROP 2 LASTPIN (3650 2575) $PN 1
J 0
(3660 2585);
DISPLAY 0.808511 (3660 2585);
FORCEPROP 2 LASTPIN (3500 2575) $PN 2
J 2
(3490 2585);
DISPLAY 0.808511 (3490 2585);
FORCEPROP 1 LAST CDS_LMAN_SYM_OUTLINE -25,50,25,-50
J 2
(3575 2575);
DISPLAY 0.468085 (3575 2575);
PAINT GREEN (3575 2575);
DISPLAY INVISIBLE (3575 2575);
FORCEPROP 2 LAST CDS_LIB pure_quanta
J 2
(3575 2575);
DISPLAY INVISIBLE (3575 2575);
FORCEPROP 1 LAST PIN_NAMES_ROTATE TRUE
J 2
(3575 2575);
DISPLAY 0.489362 (3575 2575);
PAINT GREEN (3575 2575);
DISPLAY INVISIBLE (3575 2575);
FORCEPROP 2 LAST VOLTAGE 6.3V
J 2
(3225 2625);
DISPLAY 0.553191 (3225 2625);
DISPLAY INVISIBLE (3225 2625);
FORCEPROP 1 LAST MATERIAL X6S
J 2
(3584 2654);
DISPLAY 0.574468 (3584 2654);
PAINT GREEN (3584 2654);
DISPLAY INVISIBLE (3584 2654);
FORCEPROP 2 LAST PACK_TYPE C0201
J 2
(3400 2625);
DISPLAY 0.553191 (3400 2625);
DISPLAY INVISIBLE (3400 2625);
FORCEPROP 2 LAST TOLERANCE 20%
J 2
(3500 2625);
DISPLAY 0.553191 (3500 2625);
DISPLAY INVISIBLE (3500 2625);
FORCEPROP 1 LAST PATH I368
J 2
(3575 2575);
DISPLAY 0.723404 (3575 2575);
DISPLAY INVISIBLE (3575 2575);
FORCEPROP 1 LAST $LOCATION C816
J 0
(3825 2650);
DISPLAY 1.021277 (3825 2650);
DISPLAY INVISIBLE (3825 2650);
FORCEPROP 2 LAST CDS_LOCATION C816
J 0
(3825 2650);
DISPLAY 1.021277 (3825 2650);
DISPLAY INVISIBLE (3825 2650);
FORCEPROP 2 LAST $SEC 1
J 2
(3750 2650);
DISPLAY 0.680851 (3750 2650);
PAINT MONO (3750 2650);
DISPLAY INVISIBLE (3750 2650);
FORCEPROP 2 LAST CDS_SEC 1
J 2
(3750 2650);
DISPLAY 0.680851 (3750 2650);
DISPLAY INVISIBLE (3750 2650);
FORCEADD Q_CAP_DIFFBUS..2
R 2
(3575 2725);
FORCEPROP 1 LAST PART_NUMBER SP_CH4221MEE01
J 2
(3459 2813);
DISPLAY 0.574468 (3459 2813);
PAINT GREEN (3459 2813);
DISPLAY INVISIBLE (3459 2813);
FORCEPROP 2 LAST VALUE DIFF BUS_0.22UF
J 2
(3425 2725);
DISPLAY 0.553191 (3425 2725);
FORCEPROP 1 LAST $LOCATION C815
J 2
(3809 2742);
DISPLAY 0.723404 (3809 2742);
PAINT GREEN (3809 2742);
FORCEPROP 2 LASTPIN (3650 2725) $PN 1
J 0
(3660 2735);
DISPLAY 0.808511 (3660 2735);
FORCEPROP 2 LASTPIN (3500 2725) $PN 2
J 2
(3490 2735);
DISPLAY 0.808511 (3490 2735);
FORCEPROP 2 LAST CDS_LIB pure_quanta
J 2
(3575 2725);
DISPLAY INVISIBLE (3575 2725);
FORCEPROP 1 LAST CDS_LMAN_SYM_OUTLINE -25,50,25,-50
J 2
(3575 2725);
DISPLAY 0.468085 (3575 2725);
PAINT GREEN (3575 2725);
DISPLAY INVISIBLE (3575 2725);
FORCEPROP 1 LAST PIN_NAMES_ROTATE TRUE
J 2
(3575 2725);
DISPLAY 0.489362 (3575 2725);
PAINT GREEN (3575 2725);
DISPLAY INVISIBLE (3575 2725);
FORCEPROP 2 LAST VOLTAGE 6.3V
J 2
(3225 2775);
DISPLAY 0.553191 (3225 2775);
DISPLAY INVISIBLE (3225 2775);
FORCEPROP 1 LAST MATERIAL X6S
J 2
(3584 2804);
DISPLAY 0.574468 (3584 2804);
PAINT GREEN (3584 2804);
DISPLAY INVISIBLE (3584 2804);
FORCEPROP 2 LAST PACK_TYPE C0201
J 2
(3400 2775);
DISPLAY 0.553191 (3400 2775);
DISPLAY INVISIBLE (3400 2775);
FORCEPROP 2 LAST TOLERANCE 20%
J 2
(3500 2775);
DISPLAY 0.553191 (3500 2775);
DISPLAY INVISIBLE (3500 2775);
FORCEPROP 1 LAST PATH I369
J 2
(3575 2725);
DISPLAY 0.723404 (3575 2725);
DISPLAY INVISIBLE (3575 2725);
FORCEPROP 1 LAST $LOCATION C815
J 0
(3825 2800);
DISPLAY 1.021277 (3825 2800);
DISPLAY INVISIBLE (3825 2800);
FORCEPROP 2 LAST CDS_LOCATION C815
J 0
(3825 2800);
DISPLAY 1.021277 (3825 2800);
DISPLAY INVISIBLE (3825 2800);
FORCEPROP 2 LAST $SEC 1
J 2
(3750 2800);
DISPLAY 0.680851 (3750 2800);
PAINT MONO (3750 2800);
DISPLAY INVISIBLE (3750 2800);
FORCEPROP 2 LAST CDS_SEC 1
J 2
(3750 2800);
DISPLAY 0.680851 (3750 2800);
DISPLAY INVISIBLE (3750 2800);
FORCEADD Q_CAP_DIFFBUS..2
R 2
(3575 2775);
FORCEPROP 1 LAST PART_NUMBER SP_CH4221MEE01
J 2
(3459 2863);
DISPLAY 0.574468 (3459 2863);
PAINT GREEN (3459 2863);
DISPLAY INVISIBLE (3459 2863);
FORCEPROP 2 LAST VALUE DIFF BUS_0.22UF
J 2
(3425 2775);
DISPLAY 0.553191 (3425 2775);
FORCEPROP 1 LAST $LOCATION C814
J 2
(3809 2792);
DISPLAY 0.723404 (3809 2792);
PAINT GREEN (3809 2792);
FORCEPROP 2 LASTPIN (3650 2775) $PN 1
J 0
(3660 2785);
DISPLAY 0.808511 (3660 2785);
FORCEPROP 2 LASTPIN (3500 2775) $PN 2
J 2
(3490 2785);
DISPLAY 0.808511 (3490 2785);
FORCEPROP 2 LAST CDS_LIB pure_quanta
J 2
(3575 2775);
DISPLAY INVISIBLE (3575 2775);
FORCEPROP 1 LAST CDS_LMAN_SYM_OUTLINE -25,50,25,-50
J 2
(3575 2775);
DISPLAY 0.468085 (3575 2775);
PAINT GREEN (3575 2775);
DISPLAY INVISIBLE (3575 2775);
FORCEPROP 1 LAST PIN_NAMES_ROTATE TRUE
J 2
(3575 2775);
DISPLAY 0.489362 (3575 2775);
PAINT GREEN (3575 2775);
DISPLAY INVISIBLE (3575 2775);
FORCEPROP 2 LAST VOLTAGE 6.3V
J 2
(3225 2825);
DISPLAY 0.553191 (3225 2825);
DISPLAY INVISIBLE (3225 2825);
FORCEPROP 1 LAST MATERIAL X6S
J 2
(3584 2854);
DISPLAY 0.574468 (3584 2854);
PAINT GREEN (3584 2854);
DISPLAY INVISIBLE (3584 2854);
FORCEPROP 2 LAST PACK_TYPE C0201
J 2
(3400 2825);
DISPLAY 0.553191 (3400 2825);
DISPLAY INVISIBLE (3400 2825);
FORCEPROP 2 LAST TOLERANCE 20%
J 2
(3500 2825);
DISPLAY 0.553191 (3500 2825);
DISPLAY INVISIBLE (3500 2825);
FORCEPROP 1 LAST PATH I370
J 2
(3575 2775);
DISPLAY 0.723404 (3575 2775);
DISPLAY INVISIBLE (3575 2775);
FORCEPROP 1 LAST $LOCATION C814
J 0
(3825 2850);
DISPLAY 1.021277 (3825 2850);
DISPLAY INVISIBLE (3825 2850);
FORCEPROP 2 LAST CDS_LOCATION C814
J 0
(3825 2850);
DISPLAY 1.021277 (3825 2850);
DISPLAY INVISIBLE (3825 2850);
FORCEPROP 2 LAST $SEC 1
J 2
(3750 2850);
DISPLAY 0.680851 (3750 2850);
PAINT MONO (3750 2850);
DISPLAY INVISIBLE (3750 2850);
FORCEPROP 2 LAST CDS_SEC 1
J 2
(3750 2850);
DISPLAY 0.680851 (3750 2850);
DISPLAY INVISIBLE (3750 2850);
FORCEADD Q_CAP_DIFFBUS..2
R 2
(3575 2975);
FORCEPROP 1 LAST PART_NUMBER SP_CH4221MEE01
J 2
(3459 3063);
DISPLAY 0.574468 (3459 3063);
PAINT GREEN (3459 3063);
DISPLAY INVISIBLE (3459 3063);
FORCEPROP 2 LAST VALUE DIFF BUS_0.22UF
J 2
(3425 2975);
DISPLAY 0.553191 (3425 2975);
FORCEPROP 1 LAST $LOCATION C812
J 2
(3809 2992);
DISPLAY 0.723404 (3809 2992);
PAINT GREEN (3809 2992);
FORCEPROP 2 LASTPIN (3650 2975) $PN 1
J 0
(3660 2985);
DISPLAY 0.808511 (3660 2985);
FORCEPROP 2 LASTPIN (3500 2975) $PN 2
J 2
(3490 2985);
DISPLAY 0.808511 (3490 2985);
FORCEPROP 1 LAST CDS_LMAN_SYM_OUTLINE -25,50,25,-50
J 2
(3575 2975);
DISPLAY 0.468085 (3575 2975);
PAINT GREEN (3575 2975);
DISPLAY INVISIBLE (3575 2975);
FORCEPROP 2 LAST CDS_LIB pure_quanta
J 2
(3575 2975);
DISPLAY INVISIBLE (3575 2975);
FORCEPROP 1 LAST PIN_NAMES_ROTATE TRUE
J 2
(3575 2975);
DISPLAY 0.489362 (3575 2975);
PAINT GREEN (3575 2975);
DISPLAY INVISIBLE (3575 2975);
FORCEPROP 2 LAST VOLTAGE 6.3V
J 2
(3225 3025);
DISPLAY 0.553191 (3225 3025);
DISPLAY INVISIBLE (3225 3025);
FORCEPROP 1 LAST MATERIAL X6S
J 2
(3584 3054);
DISPLAY 0.574468 (3584 3054);
PAINT GREEN (3584 3054);
DISPLAY INVISIBLE (3584 3054);
FORCEPROP 2 LAST PACK_TYPE C0201
J 2
(3400 3025);
DISPLAY 0.553191 (3400 3025);
DISPLAY INVISIBLE (3400 3025);
FORCEPROP 2 LAST TOLERANCE 20%
J 2
(3500 3025);
DISPLAY 0.553191 (3500 3025);
DISPLAY INVISIBLE (3500 3025);
FORCEPROP 1 LAST PATH I371
J 2
(3575 2975);
DISPLAY 0.723404 (3575 2975);
DISPLAY INVISIBLE (3575 2975);
FORCEPROP 1 LAST $LOCATION C812
J 0
(3825 3050);
DISPLAY 1.021277 (3825 3050);
DISPLAY INVISIBLE (3825 3050);
FORCEPROP 2 LAST CDS_LOCATION C812
J 0
(3825 3050);
DISPLAY 1.021277 (3825 3050);
DISPLAY INVISIBLE (3825 3050);
FORCEPROP 2 LAST $SEC 1
J 2
(3750 3050);
DISPLAY 0.680851 (3750 3050);
PAINT MONO (3750 3050);
DISPLAY INVISIBLE (3750 3050);
FORCEPROP 2 LAST CDS_SEC 1
J 2
(3750 3050);
DISPLAY 0.680851 (3750 3050);
DISPLAY INVISIBLE (3750 3050);
FORCEADD Q_CAP_DIFFBUS..2
R 2
(3575 2925);
FORCEPROP 1 LAST PART_NUMBER SP_CH4221MEE01
J 2
(3459 3013);
DISPLAY 0.574468 (3459 3013);
PAINT GREEN (3459 3013);
DISPLAY INVISIBLE (3459 3013);
FORCEPROP 2 LAST VALUE DIFF BUS_0.22UF
J 2
(3425 2925);
DISPLAY 0.553191 (3425 2925);
FORCEPROP 1 LAST $LOCATION C813
J 2
(3809 2942);
DISPLAY 0.723404 (3809 2942);
PAINT GREEN (3809 2942);
FORCEPROP 2 LASTPIN (3650 2925) $PN 1
J 0
(3660 2935);
DISPLAY 0.808511 (3660 2935);
FORCEPROP 2 LASTPIN (3500 2925) $PN 2
J 2
(3490 2935);
DISPLAY 0.808511 (3490 2935);
FORCEPROP 1 LAST CDS_LMAN_SYM_OUTLINE -25,50,25,-50
J 2
(3575 2925);
DISPLAY 0.468085 (3575 2925);
PAINT GREEN (3575 2925);
DISPLAY INVISIBLE (3575 2925);
FORCEPROP 2 LAST CDS_LIB pure_quanta
J 2
(3575 2925);
DISPLAY INVISIBLE (3575 2925);
FORCEPROP 1 LAST PIN_NAMES_ROTATE TRUE
J 2
(3575 2925);
DISPLAY 0.489362 (3575 2925);
PAINT GREEN (3575 2925);
DISPLAY INVISIBLE (3575 2925);
FORCEPROP 2 LAST VOLTAGE 6.3V
J 2
(3225 2975);
DISPLAY 0.553191 (3225 2975);
DISPLAY INVISIBLE (3225 2975);
FORCEPROP 1 LAST MATERIAL X6S
J 2
(3584 3004);
DISPLAY 0.574468 (3584 3004);
PAINT GREEN (3584 3004);
DISPLAY INVISIBLE (3584 3004);
FORCEPROP 2 LAST PACK_TYPE C0201
J 2
(3400 2975);
DISPLAY 0.553191 (3400 2975);
DISPLAY INVISIBLE (3400 2975);
FORCEPROP 2 LAST TOLERANCE 20%
J 2
(3500 2975);
DISPLAY 0.553191 (3500 2975);
DISPLAY INVISIBLE (3500 2975);
FORCEPROP 1 LAST PATH I372
J 2
(3575 2925);
DISPLAY 0.723404 (3575 2925);
DISPLAY INVISIBLE (3575 2925);
FORCEPROP 1 LAST $LOCATION C813
J 0
(3825 3000);
DISPLAY 1.021277 (3825 3000);
DISPLAY INVISIBLE (3825 3000);
FORCEPROP 2 LAST CDS_LOCATION C813
J 0
(3825 3000);
DISPLAY 1.021277 (3825 3000);
DISPLAY INVISIBLE (3825 3000);
FORCEPROP 2 LAST $SEC 1
J 2
(3750 3000);
DISPLAY 0.680851 (3750 3000);
PAINT MONO (3750 3000);
DISPLAY INVISIBLE (3750 3000);
FORCEPROP 2 LAST CDS_SEC 1
J 2
(3750 3000);
DISPLAY 0.680851 (3750 3000);
DISPLAY INVISIBLE (3750 3000);
FORCEADD Q_CAP_DIFFBUS..2
R 2
(3575 3125);
FORCEPROP 1 LAST PART_NUMBER SP_CH4221MEE01
J 2
(3459 3213);
DISPLAY 0.574468 (3459 3213);
PAINT GREEN (3459 3213);
DISPLAY INVISIBLE (3459 3213);
FORCEPROP 2 LAST VALUE DIFF BUS_0.22UF
J 2
(3425 3125);
DISPLAY 0.553191 (3425 3125);
FORCEPROP 1 LAST $LOCATION C811
J 2
(3809 3142);
DISPLAY 0.723404 (3809 3142);
PAINT GREEN (3809 3142);
FORCEPROP 2 LASTPIN (3650 3125) $PN 1
J 0
(3660 3135);
DISPLAY 0.808511 (3660 3135);
FORCEPROP 2 LASTPIN (3500 3125) $PN 2
J 2
(3490 3135);
DISPLAY 0.808511 (3490 3135);
FORCEPROP 1 LAST CDS_LMAN_SYM_OUTLINE -25,50,25,-50
J 2
(3575 3125);
DISPLAY 0.468085 (3575 3125);
PAINT GREEN (3575 3125);
DISPLAY INVISIBLE (3575 3125);
FORCEPROP 2 LAST CDS_LIB pure_quanta
J 2
(3575 3125);
DISPLAY INVISIBLE (3575 3125);
FORCEPROP 1 LAST PIN_NAMES_ROTATE TRUE
J 2
(3575 3125);
DISPLAY 0.489362 (3575 3125);
PAINT GREEN (3575 3125);
DISPLAY INVISIBLE (3575 3125);
FORCEPROP 2 LAST VOLTAGE 6.3V
J 2
(3225 3175);
DISPLAY 0.553191 (3225 3175);
DISPLAY INVISIBLE (3225 3175);
FORCEPROP 1 LAST MATERIAL X6S
J 2
(3584 3204);
DISPLAY 0.574468 (3584 3204);
PAINT GREEN (3584 3204);
DISPLAY INVISIBLE (3584 3204);
FORCEPROP 2 LAST PACK_TYPE C0201
J 2
(3400 3175);
DISPLAY 0.553191 (3400 3175);
DISPLAY INVISIBLE (3400 3175);
FORCEPROP 2 LAST TOLERANCE 20%
J 2
(3500 3175);
DISPLAY 0.553191 (3500 3175);
DISPLAY INVISIBLE (3500 3175);
FORCEPROP 1 LAST PATH I373
J 2
(3575 3125);
DISPLAY 0.723404 (3575 3125);
DISPLAY INVISIBLE (3575 3125);
FORCEPROP 1 LAST $LOCATION C811
J 0
(3825 3200);
DISPLAY 1.021277 (3825 3200);
DISPLAY INVISIBLE (3825 3200);
FORCEPROP 2 LAST CDS_LOCATION C811
J 0
(3825 3200);
DISPLAY 1.021277 (3825 3200);
DISPLAY INVISIBLE (3825 3200);
FORCEPROP 2 LAST $SEC 1
J 2
(3750 3200);
DISPLAY 0.680851 (3750 3200);
PAINT MONO (3750 3200);
DISPLAY INVISIBLE (3750 3200);
FORCEPROP 2 LAST CDS_SEC 1
J 2
(3750 3200);
DISPLAY 0.680851 (3750 3200);
DISPLAY INVISIBLE (3750 3200);
FORCEADD Q_CAP_DIFFBUS..2
R 2
(3575 3175);
FORCEPROP 1 LAST PART_NUMBER SP_CH4221MEE01
J 2
(3459 3263);
DISPLAY 0.574468 (3459 3263);
PAINT GREEN (3459 3263);
DISPLAY INVISIBLE (3459 3263);
FORCEPROP 2 LAST VALUE DIFF BUS_0.22UF
J 2
(3425 3175);
DISPLAY 0.553191 (3425 3175);
FORCEPROP 1 LAST $LOCATION C810
J 2
(3809 3192);
DISPLAY 0.723404 (3809 3192);
PAINT GREEN (3809 3192);
FORCEPROP 2 LASTPIN (3650 3175) $PN 1
J 0
(3660 3185);
DISPLAY 0.808511 (3660 3185);
FORCEPROP 2 LASTPIN (3500 3175) $PN 2
J 2
(3490 3185);
DISPLAY 0.808511 (3490 3185);
FORCEPROP 1 LAST CDS_LMAN_SYM_OUTLINE -25,50,25,-50
J 2
(3575 3175);
DISPLAY 0.468085 (3575 3175);
PAINT GREEN (3575 3175);
DISPLAY INVISIBLE (3575 3175);
FORCEPROP 2 LAST CDS_LIB pure_quanta
J 2
(3575 3175);
DISPLAY INVISIBLE (3575 3175);
FORCEPROP 1 LAST PIN_NAMES_ROTATE TRUE
J 2
(3575 3175);
DISPLAY 0.489362 (3575 3175);
PAINT GREEN (3575 3175);
DISPLAY INVISIBLE (3575 3175);
FORCEPROP 2 LAST VOLTAGE 6.3V
J 2
(3225 3225);
DISPLAY 0.553191 (3225 3225);
DISPLAY INVISIBLE (3225 3225);
FORCEPROP 1 LAST MATERIAL X6S
J 2
(3584 3254);
DISPLAY 0.574468 (3584 3254);
PAINT GREEN (3584 3254);
DISPLAY INVISIBLE (3584 3254);
FORCEPROP 2 LAST PACK_TYPE C0201
J 2
(3400 3225);
DISPLAY 0.553191 (3400 3225);
DISPLAY INVISIBLE (3400 3225);
FORCEPROP 2 LAST TOLERANCE 20%
J 2
(3500 3225);
DISPLAY 0.553191 (3500 3225);
DISPLAY INVISIBLE (3500 3225);
FORCEPROP 1 LAST PATH I374
J 2
(3575 3175);
DISPLAY 0.723404 (3575 3175);
DISPLAY INVISIBLE (3575 3175);
FORCEPROP 1 LAST $LOCATION C810
J 0
(3825 3250);
DISPLAY 1.021277 (3825 3250);
DISPLAY INVISIBLE (3825 3250);
FORCEPROP 2 LAST CDS_LOCATION C810
J 0
(3825 3250);
DISPLAY 1.021277 (3825 3250);
DISPLAY INVISIBLE (3825 3250);
FORCEPROP 2 LAST $SEC 1
J 2
(3750 3250);
DISPLAY 0.680851 (3750 3250);
PAINT MONO (3750 3250);
DISPLAY INVISIBLE (3750 3250);
FORCEPROP 2 LAST CDS_SEC 1
J 2
(3750 3250);
DISPLAY 0.680851 (3750 3250);
DISPLAY INVISIBLE (3750 3250);
FORCEADD Q_CAP_DIFFBUS..2
R 2
(3575 3325);
FORCEPROP 1 LAST PART_NUMBER SP_CH4221MEE01
J 2
(3459 3413);
DISPLAY 0.574468 (3459 3413);
PAINT GREEN (3459 3413);
DISPLAY INVISIBLE (3459 3413);
FORCEPROP 2 LAST VALUE DIFF BUS_0.22UF
J 2
(3425 3325);
DISPLAY 0.553191 (3425 3325);
FORCEPROP 1 LAST $LOCATION C809
J 2
(3809 3342);
DISPLAY 0.723404 (3809 3342);
PAINT GREEN (3809 3342);
FORCEPROP 2 LASTPIN (3650 3325) $PN 1
J 0
(3660 3335);
DISPLAY 0.808511 (3660 3335);
FORCEPROP 2 LASTPIN (3500 3325) $PN 2
J 2
(3490 3335);
DISPLAY 0.808511 (3490 3335);
FORCEPROP 1 LAST CDS_LMAN_SYM_OUTLINE -25,50,25,-50
J 2
(3575 3325);
DISPLAY 0.468085 (3575 3325);
PAINT GREEN (3575 3325);
DISPLAY INVISIBLE (3575 3325);
FORCEPROP 2 LAST CDS_LIB pure_quanta
J 2
(3575 3325);
DISPLAY INVISIBLE (3575 3325);
FORCEPROP 1 LAST PIN_NAMES_ROTATE TRUE
J 2
(3575 3325);
DISPLAY 0.489362 (3575 3325);
PAINT GREEN (3575 3325);
DISPLAY INVISIBLE (3575 3325);
FORCEPROP 2 LAST VOLTAGE 6.3V
J 2
(3225 3375);
DISPLAY 0.553191 (3225 3375);
DISPLAY INVISIBLE (3225 3375);
FORCEPROP 1 LAST MATERIAL X6S
J 2
(3584 3404);
DISPLAY 0.574468 (3584 3404);
PAINT GREEN (3584 3404);
DISPLAY INVISIBLE (3584 3404);
FORCEPROP 2 LAST PACK_TYPE C0201
J 2
(3400 3375);
DISPLAY 0.553191 (3400 3375);
DISPLAY INVISIBLE (3400 3375);
FORCEPROP 2 LAST TOLERANCE 20%
J 2
(3500 3375);
DISPLAY 0.553191 (3500 3375);
DISPLAY INVISIBLE (3500 3375);
FORCEPROP 1 LAST PATH I375
J 2
(3575 3325);
DISPLAY 0.723404 (3575 3325);
DISPLAY INVISIBLE (3575 3325);
FORCEPROP 1 LAST $LOCATION C809
J 0
(3825 3400);
DISPLAY 1.021277 (3825 3400);
DISPLAY INVISIBLE (3825 3400);
FORCEPROP 2 LAST CDS_LOCATION C809
J 0
(3825 3400);
DISPLAY 1.021277 (3825 3400);
DISPLAY INVISIBLE (3825 3400);
FORCEPROP 2 LAST $SEC 1
J 2
(3750 3400);
DISPLAY 0.680851 (3750 3400);
PAINT MONO (3750 3400);
DISPLAY INVISIBLE (3750 3400);
FORCEPROP 2 LAST CDS_SEC 1
J 2
(3750 3400);
DISPLAY 0.680851 (3750 3400);
DISPLAY INVISIBLE (3750 3400);
FORCEADD Q_CAP_DIFFBUS..2
R 2
(3575 3375);
FORCEPROP 1 LAST PART_NUMBER SP_CH4221MEE01
J 2
(3459 3463);
DISPLAY 0.574468 (3459 3463);
PAINT GREEN (3459 3463);
DISPLAY INVISIBLE (3459 3463);
FORCEPROP 2 LAST VALUE DIFF BUS_0.22UF
J 2
(3425 3375);
DISPLAY 0.553191 (3425 3375);
FORCEPROP 1 LAST $LOCATION C808
J 2
(3809 3392);
DISPLAY 0.723404 (3809 3392);
PAINT GREEN (3809 3392);
FORCEPROP 2 LASTPIN (3650 3375) $PN 1
J 0
(3660 3385);
DISPLAY 0.808511 (3660 3385);
FORCEPROP 2 LASTPIN (3500 3375) $PN 2
J 2
(3490 3385);
DISPLAY 0.808511 (3490 3385);
FORCEPROP 1 LAST CDS_LMAN_SYM_OUTLINE -25,50,25,-50
J 2
(3575 3375);
DISPLAY 0.468085 (3575 3375);
PAINT GREEN (3575 3375);
DISPLAY INVISIBLE (3575 3375);
FORCEPROP 2 LAST CDS_LIB pure_quanta
J 2
(3575 3375);
DISPLAY INVISIBLE (3575 3375);
FORCEPROP 1 LAST PIN_NAMES_ROTATE TRUE
J 2
(3575 3375);
DISPLAY 0.489362 (3575 3375);
PAINT GREEN (3575 3375);
DISPLAY INVISIBLE (3575 3375);
FORCEPROP 2 LAST VOLTAGE 6.3V
J 2
(3225 3425);
DISPLAY 0.553191 (3225 3425);
DISPLAY INVISIBLE (3225 3425);
FORCEPROP 1 LAST MATERIAL X6S
J 2
(3584 3454);
DISPLAY 0.574468 (3584 3454);
PAINT GREEN (3584 3454);
DISPLAY INVISIBLE (3584 3454);
FORCEPROP 2 LAST PACK_TYPE C0201
J 2
(3400 3425);
DISPLAY 0.553191 (3400 3425);
DISPLAY INVISIBLE (3400 3425);
FORCEPROP 2 LAST TOLERANCE 20%
J 2
(3500 3425);
DISPLAY 0.553191 (3500 3425);
DISPLAY INVISIBLE (3500 3425);
FORCEPROP 1 LAST PATH I376
J 2
(3575 3375);
DISPLAY 0.723404 (3575 3375);
DISPLAY INVISIBLE (3575 3375);
FORCEPROP 1 LAST $LOCATION C808
J 0
(3825 3450);
DISPLAY 1.021277 (3825 3450);
DISPLAY INVISIBLE (3825 3450);
FORCEPROP 2 LAST CDS_LOCATION C808
J 0
(3825 3450);
DISPLAY 1.021277 (3825 3450);
DISPLAY INVISIBLE (3825 3450);
FORCEPROP 2 LAST $SEC 1
J 2
(3750 3450);
DISPLAY 0.680851 (3750 3450);
PAINT MONO (3750 3450);
DISPLAY INVISIBLE (3750 3450);
FORCEPROP 2 LAST CDS_SEC 1
J 2
(3750 3450);
DISPLAY 0.680851 (3750 3450);
DISPLAY INVISIBLE (3750 3450);
FORCEADD Q_CAP_DIFFBUS..2
R 2
(3575 3575);
FORCEPROP 1 LAST PART_NUMBER SP_CH4221MEE01
J 2
(3834 3663);
DISPLAY 0.574468 (3834 3663);
PAINT GREEN (3834 3663);
DISPLAY INVISIBLE (3834 3663);
FORCEPROP 2 LAST VALUE DIFF BUS_0.22UF
J 2
(3425 3575);
DISPLAY 0.553191 (3425 3575);
FORCEPROP 1 LAST MATERIAL X6S
J 2
(3534 3779);
DISPLAY 0.574468 (3534 3779);
PAINT GREEN (3534 3779);
FORCEPROP 2 LAST PACK_TYPE C0201
J 2
(3575 3725);
DISPLAY 0.553191 (3575 3725);
PAINT GREEN (3575 3725);
FORCEPROP 2 LAST VOLTAGE 6.3V
J 2
(3825 3725);
DISPLAY 0.553191 (3825 3725);
PAINT GREEN (3825 3725);
FORCEPROP 2 LAST TOLERANCE 20%
J 2
(3675 3725);
DISPLAY 0.553191 (3675 3725);
PAINT GREEN (3675 3725);
FORCEPROP 1 LAST $LOCATION C806
J 2
(3809 3592);
DISPLAY 0.723404 (3809 3592);
PAINT GREEN (3809 3592);
FORCEPROP 2 LASTPIN (3650 3575) $PN 1
J 0
(3660 3585);
DISPLAY 0.808511 (3660 3585);
FORCEPROP 2 LASTPIN (3500 3575) $PN 2
J 2
(3490 3585);
DISPLAY 0.808511 (3490 3585);
FORCEPROP 2 LAST CDS_LIB pure_quanta
J 2
(3575 3575);
DISPLAY INVISIBLE (3575 3575);
FORCEPROP 1 LAST CDS_LMAN_SYM_OUTLINE -25,50,25,-50
J 2
(3575 3575);
DISPLAY 0.468085 (3575 3575);
PAINT GREEN (3575 3575);
DISPLAY INVISIBLE (3575 3575);
FORCEPROP 1 LAST PIN_NAMES_ROTATE TRUE
J 2
(3575 3575);
DISPLAY 0.489362 (3575 3575);
PAINT GREEN (3575 3575);
DISPLAY INVISIBLE (3575 3575);
FORCEPROP 1 LAST PATH I377
J 2
(3575 3575);
DISPLAY 0.723404 (3575 3575);
DISPLAY INVISIBLE (3575 3575);
FORCEPROP 1 LAST $LOCATION C806
J 0
(3825 3650);
DISPLAY 1.021277 (3825 3650);
DISPLAY INVISIBLE (3825 3650);
FORCEPROP 2 LAST CDS_LOCATION C806
J 0
(3550 3825);
DISPLAY 1.021277 (3550 3825);
DISPLAY INVISIBLE (3550 3825);
FORCEPROP 2 LAST $SEC 1
J 2
(3750 3650);
DISPLAY 0.680851 (3750 3650);
PAINT MONO (3750 3650);
DISPLAY INVISIBLE (3750 3650);
FORCEPROP 2 LAST CDS_SEC 1
J 2
(3750 3650);
DISPLAY 0.680851 (3750 3650);
DISPLAY INVISIBLE (3750 3650);
FORCEADD Q_CAP_DIFFBUS..2
R 2
(3575 3525);
FORCEPROP 1 LAST PART_NUMBER SP_CH4221MEE01
J 2
(3459 3613);
DISPLAY 0.574468 (3459 3613);
PAINT GREEN (3459 3613);
DISPLAY INVISIBLE (3459 3613);
FORCEPROP 2 LAST VALUE DIFF BUS_0.22UF
J 2
(3425 3525);
DISPLAY 0.553191 (3425 3525);
FORCEPROP 1 LAST $LOCATION C807
J 2
(3809 3542);
DISPLAY 0.723404 (3809 3542);
PAINT GREEN (3809 3542);
FORCEPROP 2 LASTPIN (3650 3525) $PN 1
J 0
(3660 3535);
DISPLAY 0.808511 (3660 3535);
FORCEPROP 2 LASTPIN (3500 3525) $PN 2
J 2
(3490 3535);
DISPLAY 0.808511 (3490 3535);
FORCEPROP 1 LAST CDS_LMAN_SYM_OUTLINE -25,50,25,-50
J 2
(3575 3525);
DISPLAY 0.468085 (3575 3525);
PAINT GREEN (3575 3525);
DISPLAY INVISIBLE (3575 3525);
FORCEPROP 2 LAST CDS_LIB pure_quanta
J 2
(3575 3525);
DISPLAY INVISIBLE (3575 3525);
FORCEPROP 1 LAST PIN_NAMES_ROTATE TRUE
J 2
(3575 3525);
DISPLAY 0.489362 (3575 3525);
PAINT GREEN (3575 3525);
DISPLAY INVISIBLE (3575 3525);
FORCEPROP 2 LAST VOLTAGE 6.3V
J 2
(3225 3575);
DISPLAY 0.553191 (3225 3575);
DISPLAY INVISIBLE (3225 3575);
FORCEPROP 1 LAST MATERIAL X6S
J 2
(3584 3604);
DISPLAY 0.574468 (3584 3604);
PAINT GREEN (3584 3604);
DISPLAY INVISIBLE (3584 3604);
FORCEPROP 2 LAST PACK_TYPE C0201
J 2
(3400 3575);
DISPLAY 0.553191 (3400 3575);
DISPLAY INVISIBLE (3400 3575);
FORCEPROP 2 LAST TOLERANCE 20%
J 2
(3500 3575);
DISPLAY 0.553191 (3500 3575);
DISPLAY INVISIBLE (3500 3575);
FORCEPROP 1 LAST PATH I378
J 2
(3575 3525);
DISPLAY 0.723404 (3575 3525);
DISPLAY INVISIBLE (3575 3525);
FORCEPROP 1 LAST $LOCATION C807
J 0
(3825 3600);
DISPLAY 1.021277 (3825 3600);
DISPLAY INVISIBLE (3825 3600);
FORCEPROP 2 LAST CDS_LOCATION C807
J 0
(3825 3600);
DISPLAY 1.021277 (3825 3600);
DISPLAY INVISIBLE (3825 3600);
FORCEPROP 2 LAST $SEC 1
J 2
(3750 3600);
DISPLAY 0.680851 (3750 3600);
PAINT MONO (3750 3600);
DISPLAY INVISIBLE (3750 3600);
FORCEPROP 2 LAST CDS_SEC 1
J 2
(3750 3600);
DISPLAY 0.680851 (3750 3600);
DISPLAY INVISIBLE (3750 3600);
FORCEADD TAP..1
(4125 200);
FORCEPROP 3 LASTPIN (4075 200) SIG_NAME P5E_CPU1_PE1_TX_C_DN<0>
J 0
(4085 210);
DISPLAY 0.659574 (4085 210);
PAINT MONO (4085 210);
DISPLAY INVISIBLE (4085 210);
FORCEPROP 1 LASTPIN (4075 200) BN 0
J 0
(4063 208);
DISPLAY 0.680851 (4063 208);
PAINT GREEN (4063 208);
FORCEPROP 2 LAST CDS_LIB standard
J 0
(4125 200);
DISPLAY INVISIBLE (4125 200);
FORCEPROP 1 LAST BODY_TYPE PLUMBING
J 0
(4125 250);
DISPLAY 0.872340 (4125 250);
PAINT GREEN (4125 250);
DISPLAY INVISIBLE (4125 250);
FORCEPROP 1 LAST HDL_TAP TRUE
J 0
(4450 75);
DISPLAY 0.872340 (4450 75);
DISPLAY INVISIBLE (4450 75);
FORCEPROP 1 LAST PATH I379
J 0
(4123 200);
DISPLAY 0.872340 (4123 200);
PAINT GREEN (4123 200);
DISPLAY INVISIBLE (4123 200);
FORCEADD TAP..1
(4325 150);
FORCEPROP 3 LASTPIN (4275 150) SIG_NAME P5E_CPU1_PE1_TX_C_DP<0>
J 0
(4285 160);
DISPLAY 0.659574 (4285 160);
PAINT MONO (4285 160);
DISPLAY INVISIBLE (4285 160);
FORCEPROP 1 LASTPIN (4275 150) BN 0
J 0
(4263 158);
DISPLAY 0.680851 (4263 158);
PAINT GREEN (4263 158);
FORCEPROP 2 LAST CDS_LIB standard
J 0
(4325 150);
DISPLAY INVISIBLE (4325 150);
FORCEPROP 1 LAST BODY_TYPE PLUMBING
J 0
(4325 200);
DISPLAY 0.872340 (4325 200);
PAINT GREEN (4325 200);
DISPLAY INVISIBLE (4325 200);
FORCEPROP 1 LAST HDL_TAP TRUE
J 0
(4650 25);
DISPLAY 0.872340 (4650 25);
DISPLAY INVISIBLE (4650 25);
FORCEPROP 1 LAST PATH I380
J 0
(4323 150);
DISPLAY 0.872340 (4323 150);
PAINT GREEN (4323 150);
DISPLAY INVISIBLE (4323 150);
FORCEADD TAP..1
(4125 400);
FORCEPROP 3 LASTPIN (4075 400) SIG_NAME P5E_CPU1_PE1_TX_C_DN<1>
J 0
(4085 410);
DISPLAY 0.659574 (4085 410);
PAINT MONO (4085 410);
DISPLAY INVISIBLE (4085 410);
FORCEPROP 1 LASTPIN (4075 400) BN 1
J 0
(4063 408);
DISPLAY 0.680851 (4063 408);
PAINT GREEN (4063 408);
FORCEPROP 2 LAST CDS_LIB standard
J 0
(4125 400);
DISPLAY INVISIBLE (4125 400);
FORCEPROP 1 LAST BODY_TYPE PLUMBING
J 0
(4125 450);
DISPLAY 0.872340 (4125 450);
PAINT GREEN (4125 450);
DISPLAY INVISIBLE (4125 450);
FORCEPROP 1 LAST HDL_TAP TRUE
J 0
(4450 275);
DISPLAY 0.872340 (4450 275);
DISPLAY INVISIBLE (4450 275);
FORCEPROP 1 LAST PATH I381
J 0
(4123 400);
DISPLAY 0.872340 (4123 400);
PAINT GREEN (4123 400);
DISPLAY INVISIBLE (4123 400);
FORCEADD TAP..1
(4325 350);
FORCEPROP 3 LASTPIN (4275 350) SIG_NAME P5E_CPU1_PE1_TX_C_DP<1>
J 0
(4285 360);
DISPLAY 0.659574 (4285 360);
PAINT MONO (4285 360);
DISPLAY INVISIBLE (4285 360);
FORCEPROP 1 LASTPIN (4275 350) BN 1
J 0
(4263 358);
DISPLAY 0.680851 (4263 358);
PAINT GREEN (4263 358);
FORCEPROP 2 LAST CDS_LIB standard
J 0
(4325 350);
DISPLAY INVISIBLE (4325 350);
FORCEPROP 1 LAST BODY_TYPE PLUMBING
J 0
(4325 400);
DISPLAY 0.872340 (4325 400);
PAINT GREEN (4325 400);
DISPLAY INVISIBLE (4325 400);
FORCEPROP 1 LAST HDL_TAP TRUE
J 0
(4650 225);
DISPLAY 0.872340 (4650 225);
DISPLAY INVISIBLE (4650 225);
FORCEPROP 1 LAST PATH I382
J 0
(4323 350);
DISPLAY 0.872340 (4323 350);
PAINT GREEN (4323 350);
DISPLAY INVISIBLE (4323 350);
FORCEADD TAP..1
(4125 600);
FORCEPROP 3 LASTPIN (4075 600) SIG_NAME P5E_CPU1_PE1_TX_C_DN<2>
J 0
(4085 610);
DISPLAY 0.659574 (4085 610);
PAINT MONO (4085 610);
DISPLAY INVISIBLE (4085 610);
FORCEPROP 1 LASTPIN (4075 600) BN 2
J 0
(4063 608);
DISPLAY 0.680851 (4063 608);
PAINT GREEN (4063 608);
FORCEPROP 2 LAST CDS_LIB standard
J 0
(4125 600);
DISPLAY INVISIBLE (4125 600);
FORCEPROP 1 LAST BODY_TYPE PLUMBING
J 0
(4125 650);
DISPLAY 0.872340 (4125 650);
PAINT GREEN (4125 650);
DISPLAY INVISIBLE (4125 650);
FORCEPROP 1 LAST HDL_TAP TRUE
J 0
(4450 475);
DISPLAY 0.872340 (4450 475);
DISPLAY INVISIBLE (4450 475);
FORCEPROP 1 LAST PATH I383
J 0
(4123 600);
DISPLAY 0.872340 (4123 600);
PAINT GREEN (4123 600);
DISPLAY INVISIBLE (4123 600);
FORCEADD TAP..1
(4325 550);
FORCEPROP 3 LASTPIN (4275 550) SIG_NAME P5E_CPU1_PE1_TX_C_DP<2>
J 0
(4285 560);
DISPLAY 0.659574 (4285 560);
PAINT MONO (4285 560);
DISPLAY INVISIBLE (4285 560);
FORCEPROP 1 LASTPIN (4275 550) BN 2
J 0
(4263 558);
DISPLAY 0.680851 (4263 558);
PAINT GREEN (4263 558);
FORCEPROP 2 LAST CDS_LIB standard
J 0
(4325 550);
DISPLAY INVISIBLE (4325 550);
FORCEPROP 1 LAST BODY_TYPE PLUMBING
J 0
(4325 600);
DISPLAY 0.872340 (4325 600);
PAINT GREEN (4325 600);
DISPLAY INVISIBLE (4325 600);
FORCEPROP 1 LAST HDL_TAP TRUE
J 0
(4650 425);
DISPLAY 0.872340 (4650 425);
DISPLAY INVISIBLE (4650 425);
FORCEPROP 1 LAST PATH I384
J 0
(4323 550);
DISPLAY 0.872340 (4323 550);
PAINT GREEN (4323 550);
DISPLAY INVISIBLE (4323 550);
FORCEADD TAP..1
(4325 750);
FORCEPROP 3 LASTPIN (4275 750) SIG_NAME P5E_CPU1_PE1_TX_C_DP<3>
J 0
(4285 760);
DISPLAY 0.659574 (4285 760);
PAINT MONO (4285 760);
DISPLAY INVISIBLE (4285 760);
FORCEPROP 1 LASTPIN (4275 750) BN 3
J 0
(4263 758);
DISPLAY 0.680851 (4263 758);
PAINT GREEN (4263 758);
FORCEPROP 2 LAST CDS_LIB standard
J 0
(4325 750);
DISPLAY INVISIBLE (4325 750);
FORCEPROP 1 LAST BODY_TYPE PLUMBING
J 0
(4325 800);
DISPLAY 0.872340 (4325 800);
PAINT GREEN (4325 800);
DISPLAY INVISIBLE (4325 800);
FORCEPROP 1 LAST HDL_TAP TRUE
J 0
(4650 625);
DISPLAY 0.872340 (4650 625);
DISPLAY INVISIBLE (4650 625);
FORCEPROP 1 LAST PATH I385
J 0
(4323 750);
DISPLAY 0.872340 (4323 750);
PAINT GREEN (4323 750);
DISPLAY INVISIBLE (4323 750);
FORCEADD TAP..1
(4125 800);
FORCEPROP 3 LASTPIN (4075 800) SIG_NAME P5E_CPU1_PE1_TX_C_DN<3>
J 0
(4085 810);
DISPLAY 0.659574 (4085 810);
PAINT MONO (4085 810);
DISPLAY INVISIBLE (4085 810);
FORCEPROP 1 LASTPIN (4075 800) BN 3
J 0
(4063 808);
DISPLAY 0.680851 (4063 808);
PAINT GREEN (4063 808);
FORCEPROP 2 LAST CDS_LIB standard
J 0
(4125 800);
DISPLAY INVISIBLE (4125 800);
FORCEPROP 1 LAST BODY_TYPE PLUMBING
J 0
(4125 850);
DISPLAY 0.872340 (4125 850);
PAINT GREEN (4125 850);
DISPLAY INVISIBLE (4125 850);
FORCEPROP 1 LAST HDL_TAP TRUE
J 0
(4450 675);
DISPLAY 0.872340 (4450 675);
DISPLAY INVISIBLE (4450 675);
FORCEPROP 1 LAST PATH I386
J 0
(4123 800);
DISPLAY 0.872340 (4123 800);
PAINT GREEN (4123 800);
DISPLAY INVISIBLE (4123 800);
FORCEADD TAP..1
(4325 950);
FORCEPROP 3 LASTPIN (4275 950) SIG_NAME P5E_CPU1_PE1_TX_C_DP<4>
J 0
(4285 960);
DISPLAY 0.659574 (4285 960);
PAINT MONO (4285 960);
DISPLAY INVISIBLE (4285 960);
FORCEPROP 1 LASTPIN (4275 950) BN 4
J 0
(4263 958);
DISPLAY 0.680851 (4263 958);
PAINT GREEN (4263 958);
FORCEPROP 2 LAST CDS_LIB standard
J 0
(4325 950);
DISPLAY INVISIBLE (4325 950);
FORCEPROP 1 LAST BODY_TYPE PLUMBING
J 0
(4325 1000);
DISPLAY 0.872340 (4325 1000);
PAINT GREEN (4325 1000);
DISPLAY INVISIBLE (4325 1000);
FORCEPROP 1 LAST HDL_TAP TRUE
J 0
(4650 825);
DISPLAY 0.872340 (4650 825);
DISPLAY INVISIBLE (4650 825);
FORCEPROP 1 LAST PATH I387
J 0
(4323 950);
DISPLAY 0.872340 (4323 950);
PAINT GREEN (4323 950);
DISPLAY INVISIBLE (4323 950);
FORCEADD TAP..1
(4125 1200);
FORCEPROP 3 LASTPIN (4075 1200) SIG_NAME P5E_CPU1_PE1_TX_C_DN<5>
J 0
(4085 1210);
DISPLAY 0.659574 (4085 1210);
PAINT MONO (4085 1210);
DISPLAY INVISIBLE (4085 1210);
FORCEPROP 1 LASTPIN (4075 1200) BN 5
J 0
(4063 1208);
DISPLAY 0.680851 (4063 1208);
PAINT GREEN (4063 1208);
FORCEPROP 2 LAST CDS_LIB standard
J 0
(4125 1200);
DISPLAY INVISIBLE (4125 1200);
FORCEPROP 1 LAST BODY_TYPE PLUMBING
J 0
(4125 1250);
DISPLAY 0.872340 (4125 1250);
PAINT GREEN (4125 1250);
DISPLAY INVISIBLE (4125 1250);
FORCEPROP 1 LAST HDL_TAP TRUE
J 0
(4450 1075);
DISPLAY 0.872340 (4450 1075);
DISPLAY INVISIBLE (4450 1075);
FORCEPROP 1 LAST PATH I388
J 0
(4123 1200);
DISPLAY 0.872340 (4123 1200);
PAINT GREEN (4123 1200);
DISPLAY INVISIBLE (4123 1200);
FORCEADD TAP..1
(4325 1150);
FORCEPROP 3 LASTPIN (4275 1150) SIG_NAME P5E_CPU1_PE1_TX_C_DP<5>
J 0
(4285 1160);
DISPLAY 0.659574 (4285 1160);
PAINT MONO (4285 1160);
DISPLAY INVISIBLE (4285 1160);
FORCEPROP 1 LASTPIN (4275 1150) BN 5
J 0
(4263 1158);
DISPLAY 0.680851 (4263 1158);
PAINT GREEN (4263 1158);
FORCEPROP 2 LAST CDS_LIB standard
J 0
(4325 1150);
DISPLAY INVISIBLE (4325 1150);
FORCEPROP 1 LAST BODY_TYPE PLUMBING
J 0
(4325 1200);
DISPLAY 0.872340 (4325 1200);
PAINT GREEN (4325 1200);
DISPLAY INVISIBLE (4325 1200);
FORCEPROP 1 LAST HDL_TAP TRUE
J 0
(4650 1025);
DISPLAY 0.872340 (4650 1025);
DISPLAY INVISIBLE (4650 1025);
FORCEPROP 1 LAST PATH I389
J 0
(4323 1150);
DISPLAY 0.872340 (4323 1150);
PAINT GREEN (4323 1150);
DISPLAY INVISIBLE (4323 1150);
FORCEADD TAP..1
(4125 1400);
FORCEPROP 3 LASTPIN (4075 1400) SIG_NAME P5E_CPU1_PE1_TX_C_DN<6>
J 0
(4085 1410);
DISPLAY 0.659574 (4085 1410);
PAINT MONO (4085 1410);
DISPLAY INVISIBLE (4085 1410);
FORCEPROP 1 LASTPIN (4075 1400) BN 6
J 0
(4063 1408);
DISPLAY 0.680851 (4063 1408);
PAINT GREEN (4063 1408);
FORCEPROP 2 LAST CDS_LIB standard
J 0
(4125 1400);
DISPLAY INVISIBLE (4125 1400);
FORCEPROP 1 LAST BODY_TYPE PLUMBING
J 0
(4125 1450);
DISPLAY 0.872340 (4125 1450);
PAINT GREEN (4125 1450);
DISPLAY INVISIBLE (4125 1450);
FORCEPROP 1 LAST HDL_TAP TRUE
J 0
(4450 1275);
DISPLAY 0.872340 (4450 1275);
DISPLAY INVISIBLE (4450 1275);
FORCEPROP 1 LAST PATH I390
J 0
(4123 1400);
DISPLAY 0.872340 (4123 1400);
PAINT GREEN (4123 1400);
DISPLAY INVISIBLE (4123 1400);
FORCEADD TAP..1
(4325 1350);
FORCEPROP 3 LASTPIN (4275 1350) SIG_NAME P5E_CPU1_PE1_TX_C_DP<6>
J 0
(4285 1360);
DISPLAY 0.659574 (4285 1360);
PAINT MONO (4285 1360);
DISPLAY INVISIBLE (4285 1360);
FORCEPROP 1 LASTPIN (4275 1350) BN 6
J 0
(4263 1358);
DISPLAY 0.680851 (4263 1358);
PAINT GREEN (4263 1358);
FORCEPROP 2 LAST CDS_LIB standard
J 0
(4325 1350);
DISPLAY INVISIBLE (4325 1350);
FORCEPROP 1 LAST BODY_TYPE PLUMBING
J 0
(4325 1400);
DISPLAY 0.872340 (4325 1400);
PAINT GREEN (4325 1400);
DISPLAY INVISIBLE (4325 1400);
FORCEPROP 1 LAST HDL_TAP TRUE
J 0
(4650 1225);
DISPLAY 0.872340 (4650 1225);
DISPLAY INVISIBLE (4650 1225);
FORCEPROP 1 LAST PATH I391
J 0
(4323 1350);
DISPLAY 0.872340 (4323 1350);
PAINT GREEN (4323 1350);
DISPLAY INVISIBLE (4323 1350);
FORCEADD TAP..1
(4125 1600);
FORCEPROP 3 LASTPIN (4075 1600) SIG_NAME P5E_CPU1_PE1_TX_C_DN<7>
J 0
(4085 1610);
DISPLAY 0.659574 (4085 1610);
PAINT MONO (4085 1610);
DISPLAY INVISIBLE (4085 1610);
FORCEPROP 1 LASTPIN (4075 1600) BN 7
J 0
(4063 1608);
DISPLAY 0.680851 (4063 1608);
PAINT GREEN (4063 1608);
FORCEPROP 2 LAST CDS_LIB standard
J 0
(4125 1600);
DISPLAY INVISIBLE (4125 1600);
FORCEPROP 1 LAST BODY_TYPE PLUMBING
J 0
(4125 1650);
DISPLAY 0.872340 (4125 1650);
PAINT GREEN (4125 1650);
DISPLAY INVISIBLE (4125 1650);
FORCEPROP 1 LAST HDL_TAP TRUE
J 0
(4450 1475);
DISPLAY 0.872340 (4450 1475);
DISPLAY INVISIBLE (4450 1475);
FORCEPROP 1 LAST PATH I392
J 0
(4123 1600);
DISPLAY 0.872340 (4123 1600);
PAINT GREEN (4123 1600);
DISPLAY INVISIBLE (4123 1600);
FORCEADD TAP..1
(4325 1550);
FORCEPROP 3 LASTPIN (4275 1550) SIG_NAME P5E_CPU1_PE1_TX_C_DP<7>
J 0
(4285 1560);
DISPLAY 0.659574 (4285 1560);
PAINT MONO (4285 1560);
DISPLAY INVISIBLE (4285 1560);
FORCEPROP 1 LASTPIN (4275 1550) BN 7
J 0
(4263 1558);
DISPLAY 0.680851 (4263 1558);
PAINT GREEN (4263 1558);
FORCEPROP 2 LAST CDS_LIB standard
J 0
(4325 1550);
DISPLAY INVISIBLE (4325 1550);
FORCEPROP 1 LAST BODY_TYPE PLUMBING
J 0
(4325 1600);
DISPLAY 0.872340 (4325 1600);
PAINT GREEN (4325 1600);
DISPLAY INVISIBLE (4325 1600);
FORCEPROP 1 LAST HDL_TAP TRUE
J 0
(4650 1425);
DISPLAY 0.872340 (4650 1425);
DISPLAY INVISIBLE (4650 1425);
FORCEPROP 1 LAST PATH I393
J 0
(4323 1550);
DISPLAY 0.872340 (4323 1550);
PAINT GREEN (4323 1550);
DISPLAY INVISIBLE (4323 1550);
FORCEADD OFFPAGE..2
(5325 1625);
FORCEPROP 2 LAST $XR0 159 
J 0
(5514 1625);
DISPLAY 0.638298 (5514 1625);
PAINT MONO (5514 1625);
FORCEPROP 2 LAST CDS_LIB standard
J 0
(5325 1625);
DISPLAY INVISIBLE (5325 1625);
FORCEPROP 1 LAST OFFPAGE TRUE
J 0
(5650 1500);
DISPLAY 0.872340 (5650 1500);
DISPLAY INVISIBLE (5650 1500);
FORCEPROP 1 LAST COMMENT_BODY TRUE
J 0
(5280 1530);
DISPLAY 0.872340 (5280 1530);
PAINT GREEN (5280 1530);
DISPLAY INVISIBLE (5280 1530);
FORCEPROP 2 LAST PATH I394
J 0
(5525 1675);
DISPLAY 1.021277 (5525 1675);
DISPLAY INVISIBLE (5525 1675);
FORCEADD OFFPAGE..2
(5325 1575);
FORCEPROP 2 LAST $XR0 159 
J 0
(5514 1575);
DISPLAY 0.638298 (5514 1575);
PAINT MONO (5514 1575);
FORCEPROP 2 LAST CDS_LIB standard
J 0
(5325 1575);
DISPLAY INVISIBLE (5325 1575);
FORCEPROP 1 LAST OFFPAGE TRUE
J 0
(5650 1450);
DISPLAY 0.872340 (5650 1450);
DISPLAY INVISIBLE (5650 1450);
FORCEPROP 1 LAST COMMENT_BODY TRUE
J 0
(5280 1480);
DISPLAY 0.872340 (5280 1480);
PAINT GREEN (5280 1480);
DISPLAY INVISIBLE (5280 1480);
FORCEPROP 2 LAST PATH I395
J 0
(5525 1625);
DISPLAY 1.021277 (5525 1625);
DISPLAY INVISIBLE (5525 1625);
FORCEADD TAP..1
(4125 2175);
FORCEPROP 3 LASTPIN (4075 2175) SIG_NAME P5E_CPU1_PE1_TX_C_DN<8>
J 0
(4085 2185);
DISPLAY 0.659574 (4085 2185);
PAINT MONO (4085 2185);
DISPLAY INVISIBLE (4085 2185);
FORCEPROP 1 LASTPIN (4075 2175) BN 8
J 0
(4063 2183);
DISPLAY 0.680851 (4063 2183);
PAINT GREEN (4063 2183);
FORCEPROP 2 LAST CDS_LIB standard
J 0
(4125 2175);
DISPLAY INVISIBLE (4125 2175);
FORCEPROP 1 LAST BODY_TYPE PLUMBING
J 0
(4125 2225);
DISPLAY 0.872340 (4125 2225);
PAINT GREEN (4125 2225);
DISPLAY INVISIBLE (4125 2225);
FORCEPROP 1 LAST HDL_TAP TRUE
J 0
(4450 2050);
DISPLAY 0.872340 (4450 2050);
DISPLAY INVISIBLE (4450 2050);
FORCEPROP 1 LAST PATH I396
J 0
(4123 2175);
DISPLAY 0.872340 (4123 2175);
PAINT GREEN (4123 2175);
DISPLAY INVISIBLE (4123 2175);
FORCEADD TAP..1
(4325 2125);
FORCEPROP 3 LASTPIN (4275 2125) SIG_NAME P5E_CPU1_PE1_TX_C_DP<8>
J 0
(4285 2135);
DISPLAY 0.659574 (4285 2135);
PAINT MONO (4285 2135);
DISPLAY INVISIBLE (4285 2135);
FORCEPROP 1 LASTPIN (4275 2125) BN 8
J 0
(4263 2133);
DISPLAY 0.680851 (4263 2133);
PAINT GREEN (4263 2133);
FORCEPROP 2 LAST CDS_LIB standard
J 0
(4325 2125);
DISPLAY INVISIBLE (4325 2125);
FORCEPROP 1 LAST BODY_TYPE PLUMBING
J 0
(4325 2175);
DISPLAY 0.872340 (4325 2175);
PAINT GREEN (4325 2175);
DISPLAY INVISIBLE (4325 2175);
FORCEPROP 1 LAST HDL_TAP TRUE
J 0
(4650 2000);
DISPLAY 0.872340 (4650 2000);
DISPLAY INVISIBLE (4650 2000);
FORCEPROP 1 LAST PATH I397
J 0
(4323 2125);
DISPLAY 0.872340 (4323 2125);
PAINT GREEN (4323 2125);
DISPLAY INVISIBLE (4323 2125);
FORCEADD TAP..1
(4125 2375);
FORCEPROP 3 LASTPIN (4075 2375) SIG_NAME P5E_CPU1_PE1_TX_C_DN<9>
J 0
(4085 2385);
DISPLAY 0.659574 (4085 2385);
PAINT MONO (4085 2385);
DISPLAY INVISIBLE (4085 2385);
FORCEPROP 1 LASTPIN (4075 2375) BN 9
J 0
(4063 2383);
DISPLAY 0.680851 (4063 2383);
PAINT GREEN (4063 2383);
FORCEPROP 2 LAST CDS_LIB standard
J 0
(4125 2375);
DISPLAY INVISIBLE (4125 2375);
FORCEPROP 1 LAST BODY_TYPE PLUMBING
J 0
(4125 2425);
DISPLAY 0.872340 (4125 2425);
PAINT GREEN (4125 2425);
DISPLAY INVISIBLE (4125 2425);
FORCEPROP 1 LAST HDL_TAP TRUE
J 0
(4450 2250);
DISPLAY 0.872340 (4450 2250);
DISPLAY INVISIBLE (4450 2250);
FORCEPROP 1 LAST PATH I398
J 0
(4123 2375);
DISPLAY 0.872340 (4123 2375);
PAINT GREEN (4123 2375);
DISPLAY INVISIBLE (4123 2375);
FORCEADD TAP..1
(4325 2525);
FORCEPROP 3 LASTPIN (4275 2525) SIG_NAME P5E_CPU1_PE1_TX_C_DP<10>
J 0
(4285 2535);
DISPLAY 0.659574 (4285 2535);
PAINT MONO (4285 2535);
DISPLAY INVISIBLE (4285 2535);
FORCEPROP 1 LASTPIN (4275 2525) BN 10
J 0
(4263 2533);
DISPLAY 0.680851 (4263 2533);
PAINT GREEN (4263 2533);
FORCEPROP 2 LAST CDS_LIB standard
J 0
(4325 2525);
DISPLAY INVISIBLE (4325 2525);
FORCEPROP 1 LAST BODY_TYPE PLUMBING
J 0
(4325 2575);
DISPLAY 0.872340 (4325 2575);
PAINT GREEN (4325 2575);
DISPLAY INVISIBLE (4325 2575);
FORCEPROP 1 LAST HDL_TAP TRUE
J 0
(4650 2400);
DISPLAY 0.872340 (4650 2400);
DISPLAY INVISIBLE (4650 2400);
FORCEPROP 1 LAST PATH I399
J 0
(4323 2525);
DISPLAY 0.872340 (4323 2525);
PAINT GREEN (4323 2525);
DISPLAY INVISIBLE (4323 2525);
FORCEADD TAP..1
(4325 2325);
FORCEPROP 3 LASTPIN (4275 2325) SIG_NAME P5E_CPU1_PE1_TX_C_DP<9>
J 0
(4285 2335);
DISPLAY 0.659574 (4285 2335);
PAINT MONO (4285 2335);
DISPLAY INVISIBLE (4285 2335);
FORCEPROP 1 LASTPIN (4275 2325) BN 9
J 0
(4263 2333);
DISPLAY 0.680851 (4263 2333);
PAINT GREEN (4263 2333);
FORCEPROP 2 LAST CDS_LIB standard
J 0
(4325 2325);
DISPLAY INVISIBLE (4325 2325);
FORCEPROP 1 LAST BODY_TYPE PLUMBING
J 0
(4325 2375);
DISPLAY 0.872340 (4325 2375);
PAINT GREEN (4325 2375);
DISPLAY INVISIBLE (4325 2375);
FORCEPROP 1 LAST HDL_TAP TRUE
J 0
(4650 2200);
DISPLAY 0.872340 (4650 2200);
DISPLAY INVISIBLE (4650 2200);
FORCEPROP 1 LAST PATH I400
J 0
(4323 2325);
DISPLAY 0.872340 (4323 2325);
PAINT GREEN (4323 2325);
DISPLAY INVISIBLE (4323 2325);
FORCEADD TAP..1
(4125 2575);
FORCEPROP 3 LASTPIN (4075 2575) SIG_NAME P5E_CPU1_PE1_TX_C_DN<10>
J 0
(4085 2585);
DISPLAY 0.659574 (4085 2585);
PAINT MONO (4085 2585);
DISPLAY INVISIBLE (4085 2585);
FORCEPROP 1 LASTPIN (4075 2575) BN 10
J 0
(4063 2583);
DISPLAY 0.680851 (4063 2583);
PAINT GREEN (4063 2583);
FORCEPROP 2 LAST CDS_LIB standard
J 0
(4125 2575);
DISPLAY INVISIBLE (4125 2575);
FORCEPROP 1 LAST BODY_TYPE PLUMBING
J 0
(4125 2625);
DISPLAY 0.872340 (4125 2625);
PAINT GREEN (4125 2625);
DISPLAY INVISIBLE (4125 2625);
FORCEPROP 1 LAST HDL_TAP TRUE
J 0
(4450 2450);
DISPLAY 0.872340 (4450 2450);
DISPLAY INVISIBLE (4450 2450);
FORCEPROP 1 LAST PATH I401
J 0
(4123 2575);
DISPLAY 0.872340 (4123 2575);
PAINT GREEN (4123 2575);
DISPLAY INVISIBLE (4123 2575);
FORCEADD TAP..1
(4125 2775);
FORCEPROP 3 LASTPIN (4075 2775) SIG_NAME P5E_CPU1_PE1_TX_C_DN<11>
J 0
(4085 2785);
DISPLAY 0.659574 (4085 2785);
PAINT MONO (4085 2785);
DISPLAY INVISIBLE (4085 2785);
FORCEPROP 1 LASTPIN (4075 2775) BN 11
J 0
(4063 2783);
DISPLAY 0.680851 (4063 2783);
PAINT GREEN (4063 2783);
FORCEPROP 2 LAST CDS_LIB standard
J 0
(4125 2775);
DISPLAY INVISIBLE (4125 2775);
FORCEPROP 1 LAST BODY_TYPE PLUMBING
J 0
(4125 2825);
DISPLAY 0.872340 (4125 2825);
PAINT GREEN (4125 2825);
DISPLAY INVISIBLE (4125 2825);
FORCEPROP 1 LAST HDL_TAP TRUE
J 0
(4450 2650);
DISPLAY 0.872340 (4450 2650);
DISPLAY INVISIBLE (4450 2650);
FORCEPROP 1 LAST PATH I402
J 0
(4123 2775);
DISPLAY 0.872340 (4123 2775);
PAINT GREEN (4123 2775);
DISPLAY INVISIBLE (4123 2775);
FORCEADD TAP..1
(4325 2725);
FORCEPROP 3 LASTPIN (4275 2725) SIG_NAME P5E_CPU1_PE1_TX_C_DP<11>
J 0
(4285 2735);
DISPLAY 0.659574 (4285 2735);
PAINT MONO (4285 2735);
DISPLAY INVISIBLE (4285 2735);
FORCEPROP 1 LASTPIN (4275 2725) BN 11
J 0
(4263 2733);
DISPLAY 0.680851 (4263 2733);
PAINT GREEN (4263 2733);
FORCEPROP 2 LAST CDS_LIB standard
J 0
(4325 2725);
DISPLAY INVISIBLE (4325 2725);
FORCEPROP 1 LAST BODY_TYPE PLUMBING
J 0
(4325 2775);
DISPLAY 0.872340 (4325 2775);
PAINT GREEN (4325 2775);
DISPLAY INVISIBLE (4325 2775);
FORCEPROP 1 LAST HDL_TAP TRUE
J 0
(4650 2600);
DISPLAY 0.872340 (4650 2600);
DISPLAY INVISIBLE (4650 2600);
FORCEPROP 1 LAST PATH I403
J 0
(4323 2725);
DISPLAY 0.872340 (4323 2725);
PAINT GREEN (4323 2725);
DISPLAY INVISIBLE (4323 2725);
FORCEADD TAP..1
(4125 2975);
FORCEPROP 3 LASTPIN (4075 2975) SIG_NAME P5E_CPU1_PE1_TX_C_DN<12>
J 0
(4085 2985);
DISPLAY 0.659574 (4085 2985);
PAINT MONO (4085 2985);
DISPLAY INVISIBLE (4085 2985);
FORCEPROP 1 LASTPIN (4075 2975) BN 12
J 0
(4063 2983);
DISPLAY 0.680851 (4063 2983);
PAINT GREEN (4063 2983);
FORCEPROP 2 LAST CDS_LIB standard
J 0
(4125 2975);
DISPLAY INVISIBLE (4125 2975);
FORCEPROP 1 LAST BODY_TYPE PLUMBING
J 0
(4125 3025);
DISPLAY 0.872340 (4125 3025);
PAINT GREEN (4125 3025);
DISPLAY INVISIBLE (4125 3025);
FORCEPROP 1 LAST HDL_TAP TRUE
J 0
(4450 2850);
DISPLAY 0.872340 (4450 2850);
DISPLAY INVISIBLE (4450 2850);
FORCEPROP 1 LAST PATH I404
J 0
(4123 2975);
DISPLAY 0.872340 (4123 2975);
PAINT GREEN (4123 2975);
DISPLAY INVISIBLE (4123 2975);
FORCEADD TAP..1
(4325 2925);
FORCEPROP 3 LASTPIN (4275 2925) SIG_NAME P5E_CPU1_PE1_TX_C_DP<12>
J 0
(4285 2935);
DISPLAY 0.659574 (4285 2935);
PAINT MONO (4285 2935);
DISPLAY INVISIBLE (4285 2935);
FORCEPROP 1 LASTPIN (4275 2925) BN 12
J 0
(4263 2933);
DISPLAY 0.680851 (4263 2933);
PAINT GREEN (4263 2933);
FORCEPROP 2 LAST CDS_LIB standard
J 0
(4325 2925);
DISPLAY INVISIBLE (4325 2925);
FORCEPROP 1 LAST BODY_TYPE PLUMBING
J 0
(4325 2975);
DISPLAY 0.872340 (4325 2975);
PAINT GREEN (4325 2975);
DISPLAY INVISIBLE (4325 2975);
FORCEPROP 1 LAST HDL_TAP TRUE
J 0
(4650 2800);
DISPLAY 0.872340 (4650 2800);
DISPLAY INVISIBLE (4650 2800);
FORCEPROP 1 LAST PATH I405
J 0
(4323 2925);
DISPLAY 0.872340 (4323 2925);
PAINT GREEN (4323 2925);
DISPLAY INVISIBLE (4323 2925);
FORCEADD TAP..1
(4125 3175);
FORCEPROP 3 LASTPIN (4075 3175) SIG_NAME P5E_CPU1_PE1_TX_C_DN<13>
J 0
(4085 3185);
DISPLAY 0.659574 (4085 3185);
PAINT MONO (4085 3185);
DISPLAY INVISIBLE (4085 3185);
FORCEPROP 1 LASTPIN (4075 3175) BN 13
J 0
(4063 3183);
DISPLAY 0.680851 (4063 3183);
PAINT GREEN (4063 3183);
FORCEPROP 2 LAST CDS_LIB standard
J 0
(4125 3175);
DISPLAY INVISIBLE (4125 3175);
FORCEPROP 1 LAST BODY_TYPE PLUMBING
J 0
(4125 3225);
DISPLAY 0.872340 (4125 3225);
PAINT GREEN (4125 3225);
DISPLAY INVISIBLE (4125 3225);
FORCEPROP 1 LAST HDL_TAP TRUE
J 0
(4450 3050);
DISPLAY 0.872340 (4450 3050);
DISPLAY INVISIBLE (4450 3050);
FORCEPROP 1 LAST PATH I406
J 0
(4123 3175);
DISPLAY 0.872340 (4123 3175);
PAINT GREEN (4123 3175);
DISPLAY INVISIBLE (4123 3175);
FORCEADD TAP..1
(4325 3125);
FORCEPROP 3 LASTPIN (4275 3125) SIG_NAME P5E_CPU1_PE1_TX_C_DP<13>
J 0
(4285 3135);
DISPLAY 0.659574 (4285 3135);
PAINT MONO (4285 3135);
DISPLAY INVISIBLE (4285 3135);
FORCEPROP 1 LASTPIN (4275 3125) BN 13
J 0
(4263 3133);
DISPLAY 0.680851 (4263 3133);
PAINT GREEN (4263 3133);
FORCEPROP 2 LAST CDS_LIB standard
J 0
(4325 3125);
DISPLAY INVISIBLE (4325 3125);
FORCEPROP 1 LAST BODY_TYPE PLUMBING
J 0
(4325 3175);
DISPLAY 0.872340 (4325 3175);
PAINT GREEN (4325 3175);
DISPLAY INVISIBLE (4325 3175);
FORCEPROP 1 LAST HDL_TAP TRUE
J 0
(4650 3000);
DISPLAY 0.872340 (4650 3000);
DISPLAY INVISIBLE (4650 3000);
FORCEPROP 1 LAST PATH I407
J 0
(4323 3125);
DISPLAY 0.872340 (4323 3125);
PAINT GREEN (4323 3125);
DISPLAY INVISIBLE (4323 3125);
FORCEADD TAP..1
(4325 3325);
FORCEPROP 3 LASTPIN (4275 3325) SIG_NAME P5E_CPU1_PE1_TX_C_DP<14>
J 0
(4285 3335);
DISPLAY 0.659574 (4285 3335);
PAINT MONO (4285 3335);
DISPLAY INVISIBLE (4285 3335);
FORCEPROP 1 LASTPIN (4275 3325) BN 14
J 0
(4263 3333);
DISPLAY 0.680851 (4263 3333);
PAINT GREEN (4263 3333);
FORCEPROP 2 LAST CDS_LIB standard
J 0
(4325 3325);
DISPLAY INVISIBLE (4325 3325);
FORCEPROP 1 LAST BODY_TYPE PLUMBING
J 0
(4325 3375);
DISPLAY 0.872340 (4325 3375);
PAINT GREEN (4325 3375);
DISPLAY INVISIBLE (4325 3375);
FORCEPROP 1 LAST HDL_TAP TRUE
J 0
(4650 3200);
DISPLAY 0.872340 (4650 3200);
DISPLAY INVISIBLE (4650 3200);
FORCEPROP 1 LAST PATH I408
J 0
(4323 3325);
DISPLAY 0.872340 (4323 3325);
PAINT GREEN (4323 3325);
DISPLAY INVISIBLE (4323 3325);
FORCEADD TAP..1
(4125 3575);
FORCEPROP 3 LASTPIN (4075 3575) SIG_NAME P5E_CPU1_PE1_TX_C_DN<15>
J 0
(4085 3585);
DISPLAY 0.659574 (4085 3585);
PAINT MONO (4085 3585);
DISPLAY INVISIBLE (4085 3585);
FORCEPROP 1 LASTPIN (4075 3575) BN 15
J 0
(4063 3583);
DISPLAY 0.680851 (4063 3583);
PAINT GREEN (4063 3583);
FORCEPROP 2 LAST CDS_LIB standard
J 0
(4125 3575);
DISPLAY INVISIBLE (4125 3575);
FORCEPROP 1 LAST BODY_TYPE PLUMBING
J 0
(4125 3625);
DISPLAY 0.872340 (4125 3625);
PAINT GREEN (4125 3625);
DISPLAY INVISIBLE (4125 3625);
FORCEPROP 1 LAST HDL_TAP TRUE
J 0
(4450 3450);
DISPLAY 0.872340 (4450 3450);
DISPLAY INVISIBLE (4450 3450);
FORCEPROP 1 LAST PATH I409
J 0
(4123 3575);
DISPLAY 0.872340 (4123 3575);
PAINT GREEN (4123 3575);
DISPLAY INVISIBLE (4123 3575);
FORCEADD TAP..1
(4125 3375);
FORCEPROP 3 LASTPIN (4075 3375) SIG_NAME P5E_CPU1_PE1_TX_C_DN<14>
J 0
(4085 3385);
DISPLAY 0.659574 (4085 3385);
PAINT MONO (4085 3385);
DISPLAY INVISIBLE (4085 3385);
FORCEPROP 1 LASTPIN (4075 3375) BN 14
J 0
(4063 3383);
DISPLAY 0.680851 (4063 3383);
PAINT GREEN (4063 3383);
FORCEPROP 2 LAST CDS_LIB standard
J 0
(4125 3375);
DISPLAY INVISIBLE (4125 3375);
FORCEPROP 1 LAST BODY_TYPE PLUMBING
J 0
(4125 3425);
DISPLAY 0.872340 (4125 3425);
PAINT GREEN (4125 3425);
DISPLAY INVISIBLE (4125 3425);
FORCEPROP 1 LAST HDL_TAP TRUE
J 0
(4450 3250);
DISPLAY 0.872340 (4450 3250);
DISPLAY INVISIBLE (4450 3250);
FORCEPROP 1 LAST PATH I410
J 0
(4123 3375);
DISPLAY 0.872340 (4123 3375);
PAINT GREEN (4123 3375);
DISPLAY INVISIBLE (4123 3375);
FORCEADD TAP..1
(4325 3525);
FORCEPROP 3 LASTPIN (4275 3525) SIG_NAME P5E_CPU1_PE1_TX_C_DP<15>
J 0
(4285 3535);
DISPLAY 0.659574 (4285 3535);
PAINT MONO (4285 3535);
DISPLAY INVISIBLE (4285 3535);
FORCEPROP 1 LASTPIN (4275 3525) BN 15
J 0
(4263 3533);
DISPLAY 0.680851 (4263 3533);
PAINT GREEN (4263 3533);
FORCEPROP 2 LAST CDS_LIB standard
J 0
(4325 3525);
DISPLAY INVISIBLE (4325 3525);
FORCEPROP 1 LAST BODY_TYPE PLUMBING
J 0
(4325 3575);
DISPLAY 0.872340 (4325 3575);
PAINT GREEN (4325 3575);
DISPLAY INVISIBLE (4325 3575);
FORCEPROP 1 LAST HDL_TAP TRUE
J 0
(4650 3400);
DISPLAY 0.872340 (4650 3400);
DISPLAY INVISIBLE (4650 3400);
FORCEPROP 1 LAST PATH I411
J 0
(4323 3525);
DISPLAY 0.872340 (4323 3525);
PAINT GREEN (4323 3525);
DISPLAY INVISIBLE (4323 3525);
FORCEADD OFFPAGE..2
(5325 3550);
FORCEPROP 2 LAST $XR0 159 
J 0
(5514 3550);
DISPLAY 0.638298 (5514 3550);
PAINT MONO (5514 3550);
FORCEPROP 2 LAST CDS_LIB standard
J 0
(5325 3550);
DISPLAY INVISIBLE (5325 3550);
FORCEPROP 1 LAST OFFPAGE TRUE
J 0
(5650 3425);
DISPLAY 0.872340 (5650 3425);
DISPLAY INVISIBLE (5650 3425);
FORCEPROP 1 LAST COMMENT_BODY TRUE
J 0
(5280 3455);
DISPLAY 0.872340 (5280 3455);
PAINT GREEN (5280 3455);
DISPLAY INVISIBLE (5280 3455);
FORCEPROP 2 LAST PATH I412
J 0
(5525 3600);
DISPLAY 1.021277 (5525 3600);
DISPLAY INVISIBLE (5525 3600);
FORCEADD OFFPAGE..2
(5325 3600);
FORCEPROP 2 LAST $XR0 159 
J 0
(5514 3600);
DISPLAY 0.638298 (5514 3600);
PAINT MONO (5514 3600);
FORCEPROP 2 LAST CDS_LIB standard
J 0
(5325 3600);
DISPLAY INVISIBLE (5325 3600);
FORCEPROP 1 LAST OFFPAGE TRUE
J 0
(5650 3475);
DISPLAY 0.872340 (5650 3475);
DISPLAY INVISIBLE (5650 3475);
FORCEPROP 1 LAST COMMENT_BODY TRUE
J 0
(5280 3505);
DISPLAY 0.872340 (5280 3505);
PAINT GREEN (5280 3505);
DISPLAY INVISIBLE (5280 3505);
FORCEPROP 2 LAST PATH I413
J 0
(5525 3650);
DISPLAY 1.021277 (5525 3650);
DISPLAY INVISIBLE (5525 3650);
FORCEADD TAP..1
(4125 1000);
FORCEPROP 3 LASTPIN (4075 1000) SIG_NAME P5E_CPU1_PE1_TX_C_DN<4>
J 0
(4085 1010);
DISPLAY 0.659574 (4085 1010);
PAINT MONO (4085 1010);
DISPLAY INVISIBLE (4085 1010);
FORCEPROP 1 LASTPIN (4075 1000) BN 4
J 0
(4063 1008);
DISPLAY 0.680851 (4063 1008);
PAINT GREEN (4063 1008);
FORCEPROP 2 LAST CDS_LIB standard
J 0
(4125 1000);
DISPLAY INVISIBLE (4125 1000);
FORCEPROP 1 LAST BODY_TYPE PLUMBING
J 0
(4125 1050);
DISPLAY 0.872340 (4125 1050);
PAINT GREEN (4125 1050);
DISPLAY INVISIBLE (4125 1050);
FORCEPROP 1 LAST HDL_TAP TRUE
J 0
(4450 875);
DISPLAY 0.872340 (4450 875);
DISPLAY INVISIBLE (4450 875);
FORCEPROP 1 LAST PATH I414
J 0
(4123 1000);
DISPLAY 0.872340 (4123 1000);
PAINT GREEN (4123 1000);
DISPLAY INVISIBLE (4123 1000);
FORCEADD Q_CAP_DIFFBUS..2
R 2
(3575 1350);
FORCEPROP 1 LAST PART_NUMBER SP_CH4221MEE01
J 2
(3459 1438);
DISPLAY 0.574468 (3459 1438);
PAINT GREEN (3459 1438);
DISPLAY INVISIBLE (3459 1438);
FORCEPROP 2 LAST VALUE DIFF BUS_0.22UF
J 2
(3425 1350);
DISPLAY 0.553191 (3425 1350);
FORCEPROP 1 LAST $LOCATION C825
J 2
(3809 1367);
DISPLAY 0.723404 (3809 1367);
PAINT GREEN (3809 1367);
FORCEPROP 2 LASTPIN (3650 1350) $PN 1
J 0
(3660 1360);
DISPLAY 0.808511 (3660 1360);
FORCEPROP 2 LASTPIN (3500 1350) $PN 2
J 2
(3490 1360);
DISPLAY 0.808511 (3490 1360);
FORCEPROP 1 LAST PIN_NAMES_ROTATE TRUE
J 2
(3575 1350);
DISPLAY 0.489362 (3575 1350);
PAINT GREEN (3575 1350);
DISPLAY INVISIBLE (3575 1350);
FORCEPROP 2 LAST CDS_LIB pure_quanta
J 2
(3575 1350);
DISPLAY INVISIBLE (3575 1350);
FORCEPROP 1 LAST CDS_LMAN_SYM_OUTLINE -25,50,25,-50
J 2
(3575 1350);
DISPLAY 0.468085 (3575 1350);
PAINT GREEN (3575 1350);
DISPLAY INVISIBLE (3575 1350);
FORCEPROP 2 LAST VOLTAGE 6.3V
J 2
(3225 1400);
DISPLAY 0.553191 (3225 1400);
DISPLAY INVISIBLE (3225 1400);
FORCEPROP 1 LAST MATERIAL X6S
J 2
(3584 1429);
DISPLAY 0.574468 (3584 1429);
PAINT GREEN (3584 1429);
DISPLAY INVISIBLE (3584 1429);
FORCEPROP 2 LAST PACK_TYPE C0201
J 2
(3400 1400);
DISPLAY 0.553191 (3400 1400);
DISPLAY INVISIBLE (3400 1400);
FORCEPROP 2 LAST TOLERANCE 20%
J 2
(3500 1400);
DISPLAY 0.553191 (3500 1400);
DISPLAY INVISIBLE (3500 1400);
FORCEPROP 1 LAST PATH I415
J 2
(3575 1350);
DISPLAY 0.723404 (3575 1350);
DISPLAY INVISIBLE (3575 1350);
FORCEPROP 1 LAST $LOCATION C825
J 0
(3825 1425);
DISPLAY 1.021277 (3825 1425);
DISPLAY INVISIBLE (3825 1425);
FORCEPROP 2 LAST CDS_LOCATION C825
J 0
(3825 1425);
DISPLAY 1.021277 (3825 1425);
DISPLAY INVISIBLE (3825 1425);
FORCEPROP 2 LAST $SEC 1
J 2
(3750 1425);
DISPLAY 0.680851 (3750 1425);
PAINT MONO (3750 1425);
DISPLAY INVISIBLE (3750 1425);
FORCEPROP 2 LAST CDS_SEC 1
J 2
(3750 1425);
DISPLAY 0.680851 (3750 1425);
DISPLAY INVISIBLE (3750 1425);
FORCEADD Q_CAP_DIFFBUS..2
R 2
(3575 1400);
FORCEPROP 1 LAST PART_NUMBER SP_CH4221MEE01
J 2
(3459 1488);
DISPLAY 0.574468 (3459 1488);
PAINT GREEN (3459 1488);
DISPLAY INVISIBLE (3459 1488);
FORCEPROP 2 LAST VALUE DIFF BUS_0.22UF
J 2
(3425 1400);
DISPLAY 0.553191 (3425 1400);
FORCEPROP 1 LAST $LOCATION C824
J 2
(3809 1417);
DISPLAY 0.723404 (3809 1417);
PAINT GREEN (3809 1417);
FORCEPROP 2 LASTPIN (3650 1400) $PN 1
J 0
(3660 1410);
DISPLAY 0.808511 (3660 1410);
FORCEPROP 2 LASTPIN (3500 1400) $PN 2
J 2
(3490 1410);
DISPLAY 0.808511 (3490 1410);
FORCEPROP 1 LAST PIN_NAMES_ROTATE TRUE
J 2
(3575 1400);
DISPLAY 0.489362 (3575 1400);
PAINT GREEN (3575 1400);
DISPLAY INVISIBLE (3575 1400);
FORCEPROP 2 LAST CDS_LIB pure_quanta
J 2
(3575 1400);
DISPLAY INVISIBLE (3575 1400);
FORCEPROP 1 LAST CDS_LMAN_SYM_OUTLINE -25,50,25,-50
J 2
(3575 1400);
DISPLAY 0.468085 (3575 1400);
PAINT GREEN (3575 1400);
DISPLAY INVISIBLE (3575 1400);
FORCEPROP 2 LAST VOLTAGE 6.3V
J 2
(3225 1450);
DISPLAY 0.553191 (3225 1450);
DISPLAY INVISIBLE (3225 1450);
FORCEPROP 1 LAST MATERIAL X6S
J 2
(3584 1479);
DISPLAY 0.574468 (3584 1479);
PAINT GREEN (3584 1479);
DISPLAY INVISIBLE (3584 1479);
FORCEPROP 2 LAST PACK_TYPE C0201
J 2
(3400 1450);
DISPLAY 0.553191 (3400 1450);
DISPLAY INVISIBLE (3400 1450);
FORCEPROP 2 LAST TOLERANCE 20%
J 2
(3500 1450);
DISPLAY 0.553191 (3500 1450);
DISPLAY INVISIBLE (3500 1450);
FORCEPROP 1 LAST PATH I416
J 2
(3575 1400);
DISPLAY 0.723404 (3575 1400);
DISPLAY INVISIBLE (3575 1400);
FORCEPROP 1 LAST $LOCATION C824
J 0
(3825 1475);
DISPLAY 1.021277 (3825 1475);
DISPLAY INVISIBLE (3825 1475);
FORCEPROP 2 LAST CDS_LOCATION C824
J 0
(3825 1475);
DISPLAY 1.021277 (3825 1475);
DISPLAY INVISIBLE (3825 1475);
FORCEPROP 2 LAST $SEC 1
J 2
(3750 1475);
DISPLAY 0.680851 (3750 1475);
PAINT MONO (3750 1475);
DISPLAY INVISIBLE (3750 1475);
FORCEPROP 2 LAST CDS_SEC 1
J 2
(3750 1475);
DISPLAY 0.680851 (3750 1475);
DISPLAY INVISIBLE (3750 1475);
FORCEADD QUANTA_TITLE_BLOCK_C..1
(5900 -1700);
FORCEPROP 0 LAST CDS_CON_LAST_MODIFIED Fri Aug 25 14:02:46 2023
J 0
(4015 -1685);
DISPLAY INVISIBLE (4015 -1685);
FORCEPROP 1 LAST CUSTOM_TXT_CDS <CON_LAST_MODIFIED>
J 0
(4015 -1685);
DISPLAY 0.978723 (4015 -1685);
FORCEPROP 2 LAST CUSTOM_TXT_CDS <XR_PAGE_TITLE>
J 0
(-1990 3550);
DISPLAY 0.638298 (-1990 3550);
PAINT PINK (-1990 3550);
DISPLAY INVISIBLE (-1990 3550);
FORCEPROP 2 LAST CUSTOM_TXT_CDS <Q_NUMBER>
J 0
(4497 -1597);
DISPLAY 1.212766 (4497 -1597);
FORCEPROP 1 LAST CUSTOM_TXT_CDS <NAME_2>
J 0
(2725 -1650);
FORCEPROP 1 LAST CUSTOM_TXT_CDS <NAME_1>
J 0
(2725 -1525);
FORCEPROP 1 LAST CUSTOM_TXT_CDS <Q_PROJ>
J 0
(3518 -1598);
DISPLAY 1.212766 (3518 -1598);
FORCEPROP 1 LAST CUSTOM_TXT_CDS <Q_REV>
J 0
(5716 -1597);
DISPLAY 1.212766 (5716 -1597);
FORCEPROP 1 LAST CUSTOM_TXT_CDS <CON_PAGE_NUM> OF <CON_TOTAL_PAGES>
J 0
(5454 -1682);
DISPLAY 0.978723 (5454 -1682);
FORCEPROP 1 LAST Q_TITLE PCIE AC-COUPLE CAPS 3/5
J 0
(-3466 -1674);
DISPLAY 2.446809 (-3466 -1674);
PAINT GREEN (-3466 -1674);
FORCEPROP 1 LAST Q_DEPT 
J 1
(2137 -1651);
DISPLAY 1.957447 (2137 -1651);
PAINT GREEN (2137 -1651);
FORCEPROP 2 LAST CDS_XR_PAGE_TITLE CR-175 : @S9S_MB_2U_LIB.S9S_MB_2U(SCH_1):PAGE175
J 0
(-1990 3550);
DISPLAY 0.638298 (-1990 3550);
PAINT PINK (-1990 3550);
DISPLAY INVISIBLE (-1990 3550);
FORCEPROP 1 LAST COMMENT_BODY TRUE
J 0
(5912 -1713);
DISPLAY 0.978723 (5912 -1713);
PAINT GREEN (5912 -1713);
DISPLAY INVISIBLE (5912 -1713);
FORCEPROP 2 LAST PAGE_BORDER TRUE
J 0
(-1990 3550);
DISPLAY 0.638298 (-1990 3550);
PAINT PINK (-1990 3550);
DISPLAY INVISIBLE (-1990 3550);
FORCEPROP 1 LAST CDS_LMAN_SYM_OUTLINE -9475,6775,100,-125
J 0
(5900 -1700);
DISPLAY 0.468085 (5900 -1700);
PAINT GREEN (5900 -1700);
DISPLAY INVISIBLE (5900 -1700);
FORCEPROP 2 LAST CDS_LIB pure_quanta
J 0
(5900 -1700);
DISPLAY INVISIBLE (5900 -1700);
WIRE 17 -1 (-1950 175)(-1950 375);
WIRE 17 -1 (-1950 375)(-1950 575);
WIRE 17 -1 (-1950 575)(-1950 775);
WIRE 17 -1 (-1950 775)(-1950 975);
WIRE 17 -1 (-1950 975)(-1950 1175);
WIRE 17 -1 (-1950 1175)(-1950 1375);
WIRE 17 -1 (-1950 1375)(-1950 1575);
WIRE 17 -1 (-2800 1575)(-1950 1575);
FORCEPROP 2 LAST SIG_NAME P5E_CPU0_PE4_TX_DP<7:0>
J 0
(-2760 1585);
DISPLAY 0.680851 (-2760 1585);
PAINT WHITE (-2760 1585);
WIRE 17 -1 (-1700 425)(-1700 225);
WIRE 17 -1 (-1700 625)(-1700 425);
WIRE 17 -1 (-1700 825)(-1700 625);
WIRE 17 -1 (-1700 825)(-1700 1025);
WIRE 17 -1 (-1700 1225)(-1700 1025);
WIRE 17 -1 (-1700 1425)(-1700 1225);
WIRE 17 -1 (-1700 1625)(-1700 1425);
WIRE 17 -1 (-2800 1625)(-1700 1625);
FORCEPROP 2 LAST SIG_NAME P5E_CPU0_PE4_TX_DN<7:0>
J 0
(-2760 1635);
DISPLAY 0.680851 (-2760 1635);
PAINT WHITE (-2760 1635);
WIRE 17 -1 (-1700 3600)(-1700 3400);
WIRE 17 -1 (-2800 3600)(-1700 3600);
FORCEPROP 2 LAST SIG_NAME P5E_CPU0_PE4_TX_DN<15:8>
J 0
(-2760 3610);
DISPLAY 0.680851 (-2760 3610);
PAINT WHITE (-2760 3610);
WIRE 17 -1 (-1700 3400)(-1700 3200);
WIRE 17 -1 (-1700 3200)(-1700 3000);
WIRE 17 -1 (-1700 2800)(-1700 3000);
WIRE 17 -1 (-1700 2800)(-1700 2600);
WIRE 17 -1 (-1700 2600)(-1700 2400);
WIRE 17 -1 (-1700 2400)(-1700 2200);
WIRE 17 -1 (-1950 2950)(-1950 3150);
WIRE 17 -1 (-1950 2750)(-1950 2950);
WIRE 17 -1 (-1950 3150)(-1950 3350);
WIRE 17 -1 (-1950 3350)(-1950 3550);
WIRE 17 -1 (-1950 2550)(-1950 2750);
WIRE 17 -1 (-1950 2350)(-1950 2550);
WIRE 17 -1 (-2800 3550)(-1950 3550);
FORCEPROP 2 LAST SIG_NAME P5E_CPU0_PE4_TX_DP<15:8>
J 0
(-2760 3560);
DISPLAY 0.680851 (-2760 3560);
PAINT WHITE (-2760 3560);
WIRE 17 -1 (-1950 2150)(-1950 2350);
WIRE 17 -1 (-325 3600)(-325 3400);
WIRE 17 -1 (-325 3600)(775 3600);
FORCEPROP 2 LAST SIG_NAME P5E_CPU0_PE4_TX_C_DN<15:8>
J 0
(-85 3610);
DISPLAY 0.680851 (-85 3610);
PAINT WHITE (-85 3610);
WIRE 17 -1 (-125 3550)(-125 3350);
WIRE 17 -1 (-125 3550)(775 3550);
FORCEPROP 2 LAST SIG_NAME P5E_CPU0_PE4_TX_C_DP<15:8>
J 0
(-85 3560);
DISPLAY 0.680851 (-85 3560);
PAINT WHITE (-85 3560);
WIRE 17 -1 (-325 2600)(-325 2400);
WIRE 17 -1 (-325 2800)(-325 2600);
WIRE 17 -1 (-325 2400)(-325 2200);
WIRE 17 -1 (-325 2800)(-325 3000);
WIRE 17 -1 (-325 3200)(-325 3000);
WIRE 17 -1 (-325 3400)(-325 3200);
WIRE 17 -1 (-125 3350)(-125 3150);
WIRE 17 -1 (-125 3150)(-125 2950);
WIRE 17 -1 (-125 2750)(-125 2950);
WIRE 17 -1 (-125 2750)(-125 2550);
WIRE 17 -1 (-125 2550)(-125 2350);
WIRE 17 -1 (-125 2350)(-125 2150);
WIRE 17 -1 (-325 1425)(-325 1225);
WIRE 17 -1 (-325 1625)(-325 1425);
WIRE 17 -1 (-325 1225)(-325 1025);
WIRE 17 -1 (-325 825)(-325 1025);
WIRE 17 -1 (-325 1625)(775 1625);
FORCEPROP 2 LAST SIG_NAME P5E_CPU0_PE4_TX_C_DN<7:0>
J 0
(-85 1635);
DISPLAY 0.680851 (-85 1635);
PAINT WHITE (-85 1635);
WIRE 17 -1 (-325 825)(-325 625);
WIRE 17 -1 (-125 1175)(-125 975);
WIRE 17 -1 (-125 1375)(-125 1175);
WIRE 17 -1 (-125 775)(-125 975);
WIRE 17 -1 (-125 775)(-125 575);
WIRE 17 -1 (-125 1575)(-125 1375);
WIRE 17 -1 (-125 1575)(775 1575);
FORCEPROP 2 LAST SIG_NAME P5E_CPU0_PE4_TX_C_DP<7:0>
J 0
(-85 1585);
DISPLAY 0.680851 (-85 1585);
PAINT WHITE (-85 1585);
WIRE 17 -1 (-325 625)(-325 425);
WIRE 17 -1 (-325 425)(-325 225);
WIRE 17 -1 (-125 575)(-125 375);
WIRE 17 -1 (-125 375)(-125 175);
WIRE 17 -1 (2550 175)(2550 375);
WIRE 17 -1 (2550 375)(2550 575);
WIRE 17 -1 (2550 575)(2550 775);
WIRE 17 -1 (2550 775)(2550 975);
WIRE 17 -1 (2550 975)(2550 1175);
WIRE 17 -1 (2550 1175)(2550 1375);
WIRE 17 -1 (2550 1375)(2550 1575);
WIRE 17 -1 (1700 1575)(2550 1575);
FORCEPROP 2 LAST SIG_NAME P5E_CPU1_PE1_TX_DP<7:0>
J 0
(1740 1585);
DISPLAY 0.680851 (1740 1585);
PAINT WHITE (1740 1585);
WIRE 17 -1 (2800 425)(2800 225);
WIRE 17 -1 (2800 625)(2800 425);
WIRE 17 -1 (2800 825)(2800 625);
WIRE 17 -1 (2800 825)(2800 1025);
WIRE 17 -1 (2800 1225)(2800 1025);
WIRE 17 -1 (2800 1425)(2800 1225);
WIRE 17 -1 (2800 1625)(2800 1425);
WIRE 17 -1 (1700 1625)(2800 1625);
FORCEPROP 2 LAST SIG_NAME P5E_CPU1_PE1_TX_DN<7:0>
J 0
(1740 1635);
DISPLAY 0.680851 (1740 1635);
PAINT WHITE (1740 1635);
WIRE 17 -1 (2550 2350)(2550 2550);
WIRE 17 -1 (2550 2150)(2550 2350);
WIRE 17 -1 (2550 2550)(2550 2750);
WIRE 17 -1 (2550 2750)(2550 2950);
WIRE 17 -1 (2550 2950)(2550 3150);
WIRE 17 -1 (2550 3150)(2550 3350);
WIRE 17 -1 (2550 3350)(2550 3550);
WIRE 17 -1 (1700 3550)(2550 3550);
FORCEPROP 2 LAST SIG_NAME P5E_CPU1_PE1_TX_DP<15:8>
J 0
(1740 3560);
DISPLAY 0.680851 (1740 3560);
PAINT WHITE (1740 3560);
WIRE 17 -1 (2800 2600)(2800 2400);
WIRE 17 -1 (2800 2800)(2800 2600);
WIRE 17 -1 (2800 2400)(2800 2200);
WIRE 17 -1 (2800 2800)(2800 3000);
WIRE 17 -1 (2800 3200)(2800 3000);
WIRE 17 -1 (2800 3400)(2800 3200);
WIRE 17 -1 (2800 3600)(2800 3400);
WIRE 17 -1 (1700 3600)(2800 3600);
FORCEPROP 2 LAST SIG_NAME P5E_CPU1_PE1_TX_DN<15:8>
J 0
(1740 3610);
DISPLAY 0.680851 (1740 3610);
PAINT WHITE (1740 3610);
WIRE 17 -1 (4175 425)(4175 225);
WIRE 17 -1 (4175 625)(4175 425);
WIRE 17 -1 (4175 825)(4175 625);
WIRE 17 -1 (4175 825)(4175 1025);
WIRE 17 -1 (4175 1225)(4175 1025);
WIRE 17 -1 (4175 1425)(4175 1225);
WIRE 17 -1 (4175 1625)(4175 1425);
WIRE 17 -1 (4175 1625)(5275 1625);
FORCEPROP 2 LAST SIG_NAME P5E_CPU1_PE1_TX_C_DN<7:0>
J 0
(4415 1635);
DISPLAY 0.680851 (4415 1635);
PAINT WHITE (4415 1635);
WIRE 17 -1 (4375 1575)(4375 1375);
WIRE 17 -1 (4375 1575)(5275 1575);
FORCEPROP 2 LAST SIG_NAME P5E_CPU1_PE1_TX_C_DP<7:0>
J 0
(4415 1585);
DISPLAY 0.680851 (4415 1585);
PAINT WHITE (4415 1585);
WIRE 17 -1 (4175 2400)(4175 2200);
WIRE 17 -1 (4175 2600)(4175 2400);
WIRE 17 -1 (4175 2800)(4175 2600);
WIRE 17 -1 (4175 2800)(4175 3000);
WIRE 17 -1 (4175 3200)(4175 3000);
WIRE 17 -1 (4175 3400)(4175 3200);
WIRE 17 -1 (4175 3600)(4175 3400);
WIRE 17 -1 (4175 3600)(5275 3600);
FORCEPROP 2 LAST SIG_NAME P5E_CPU1_PE1_TX_C_DN<15:8>
J 0
(4415 3610);
DISPLAY 0.680851 (4415 3610);
PAINT WHITE (4415 3610);
WIRE 17 -1 (4375 2750)(4375 2950);
WIRE 17 -1 (4375 2750)(4375 2550);
WIRE 17 -1 (4375 3150)(4375 2950);
WIRE 17 -1 (4375 3350)(4375 3150);
WIRE 17 -1 (4375 2550)(4375 2350);
WIRE 17 -1 (4375 2350)(4375 2150);
WIRE 17 -1 (4375 3550)(4375 3350);
WIRE 17 -1 (4375 3550)(5275 3550);
FORCEPROP 2 LAST SIG_NAME P5E_CPU1_PE1_TX_C_DP<15:8>
J 0
(4415 3560);
DISPLAY 0.680851 (4415 3560);
PAINT WHITE (4415 3560);
WIRE 17 -1 (4375 1175)(4375 975);
WIRE 17 -1 (4375 1375)(4375 1175);
WIRE 17 -1 (4375 775)(4375 975);
WIRE 17 -1 (4375 775)(4375 575);
WIRE 17 -1 (4375 575)(4375 375);
WIRE 17 -1 (4375 375)(4375 175);
WIRE 16 -1 (-850 1150)(-225 1150);
WIRE 16 -1 (-1000 1400)(-1600 1400);
WIRE 16 -1 (3650 3525)(4275 3525);
WIRE 16 -1 (3650 3325)(4275 3325);
WIRE 16 -1 (3650 3125)(4275 3125);
WIRE 16 -1 (3650 2975)(4075 2975);
WIRE 16 -1 (3650 2775)(4075 2775);
WIRE 16 -1 (3650 2725)(4275 2725);
WIRE 16 -1 (3650 2525)(4275 2525);
WIRE 16 -1 (3650 2325)(4275 2325);
WIRE 16 -1 (3650 2125)(4275 2125);
WIRE 16 -1 (3650 1150)(4275 1150);
WIRE 16 -1 (3650 150)(4275 150);
WIRE 16 -1 (3650 350)(4275 350);
WIRE 16 -1 (3650 550)(4275 550);
WIRE 16 -1 (3650 750)(4275 750);
WIRE 16 -1 (3500 1550)(2650 1550);
WIRE 16 -1 (3500 1600)(2900 1600);
WIRE 16 -1 (3650 1200)(4075 1200);
WIRE 16 -1 (3650 950)(4275 950);
WIRE 16 -1 (3650 3575)(4075 3575);
WIRE 16 -1 (3650 3375)(4075 3375);
WIRE 16 -1 (3650 3175)(4075 3175);
WIRE 16 -1 (3650 2925)(4275 2925);
WIRE 16 -1 (3650 2575)(4075 2575);
WIRE 16 -1 (3650 2375)(4075 2375);
WIRE 16 -1 (3650 2175)(4075 2175);
WIRE 16 -1 (3650 1600)(4075 1600);
WIRE 16 -1 (3650 1550)(4275 1550);
WIRE 16 -1 (3650 1350)(4275 1350);
WIRE 16 -1 (3650 1400)(4075 1400);
WIRE 16 -1 (3650 1000)(4075 1000);
WIRE 16 -1 (3650 800)(4075 800);
WIRE 16 -1 (3650 600)(4075 600);
WIRE 16 -1 (3650 400)(4075 400);
WIRE 16 -1 (3650 200)(4075 200);
WIRE 16 -1 (3500 3575)(2900 3575);
WIRE 16 -1 (3500 3375)(2900 3375);
WIRE 16 -1 (3500 3175)(2900 3175);
WIRE 16 -1 (3500 3125)(2650 3125);
WIRE 16 -1 (3500 3525)(2650 3525);
WIRE 16 -1 (3500 3325)(2650 3325);
WIRE 16 -1 (3500 2975)(2900 2975);
WIRE 16 -1 (3500 2575)(2900 2575);
WIRE 16 -1 (3500 2775)(2900 2775);
WIRE 16 -1 (3500 2925)(2650 2925);
WIRE 16 -1 (3500 2725)(2650 2725);
WIRE 16 -1 (3500 2125)(2650 2125);
WIRE 16 -1 (3500 2175)(2900 2175);
WIRE 16 -1 (3500 2325)(2650 2325);
WIRE 16 -1 (3500 2375)(2900 2375);
WIRE 16 -1 (3500 2525)(2650 2525);
WIRE 16 -1 (3500 1400)(2900 1400);
WIRE 16 -1 (3500 1200)(2900 1200);
WIRE 16 -1 (3500 1350)(2650 1350);
WIRE 16 -1 (3500 1150)(2650 1150);
WIRE 16 -1 (3500 1000)(2900 1000);
WIRE 16 -1 (3500 800)(2900 800);
WIRE 16 -1 (3500 600)(2900 600);
WIRE 16 -1 (3500 400)(2900 400);
WIRE 16 -1 (3500 200)(2900 200);
WIRE 16 -1 (3500 750)(2650 750);
WIRE 16 -1 (3500 950)(2650 950);
WIRE 16 -1 (3500 550)(2650 550);
WIRE 16 -1 (3500 350)(2650 350);
WIRE 16 -1 (3500 150)(2650 150);
WIRE 16 -1 (-1000 3125)(-1850 3125);
WIRE 16 -1 (-850 2725)(-225 2725);
WIRE 16 -1 (-1000 2525)(-1850 2525);
WIRE 16 -1 (-850 2325)(-225 2325);
WIRE 16 -1 (-1000 1550)(-1850 1550);
WIRE 16 -1 (-1000 1000)(-1600 1000);
WIRE 16 -1 (-1000 950)(-1850 950);
WIRE 16 -1 (-1000 750)(-1850 750);
WIRE 16 -1 (-1000 600)(-1600 600);
WIRE 16 -1 (-1000 400)(-1600 400);
WIRE 16 -1 (-1000 350)(-1850 350);
WIRE 16 -1 (-1000 550)(-1850 550);
WIRE 16 -1 (-850 1350)(-225 1350);
WIRE 16 -1 (-850 1400)(-425 1400);
WIRE 16 -1 (-850 1550)(-225 1550);
WIRE 16 -1 (-850 1600)(-425 1600);
WIRE 16 -1 (-850 2125)(-225 2125);
WIRE 16 -1 (-850 2175)(-425 2175);
WIRE 16 -1 (-850 3525)(-225 3525);
WIRE 16 -1 (-850 3575)(-425 3575);
WIRE 16 -1 (-850 150)(-225 150);
WIRE 16 -1 (-850 200)(-425 200);
WIRE 16 -1 (-850 350)(-225 350);
WIRE 16 -1 (-850 400)(-425 400);
WIRE 16 -1 (-850 550)(-225 550);
WIRE 16 -1 (-850 600)(-425 600);
WIRE 16 -1 (-850 750)(-225 750);
WIRE 16 -1 (-850 800)(-425 800);
WIRE 16 -1 (-850 950)(-225 950);
WIRE 16 -1 (-850 1000)(-425 1000);
WIRE 16 -1 (-850 1200)(-425 1200);
WIRE 16 -1 (-850 2525)(-225 2525);
WIRE 16 -1 (-850 2575)(-425 2575);
WIRE 16 -1 (-850 2775)(-425 2775);
WIRE 16 -1 (-850 2925)(-225 2925);
WIRE 16 -1 (-850 2975)(-425 2975);
WIRE 16 -1 (-850 3125)(-225 3125);
WIRE 16 -1 (-850 3175)(-425 3175);
WIRE 16 -1 (-850 2375)(-425 2375);
WIRE 16 -1 (-850 3325)(-225 3325);
WIRE 16 -1 (-850 3375)(-425 3375);
WIRE 16 -1 (-1000 2775)(-1600 2775);
WIRE 16 -1 (-1000 3325)(-1850 3325);
WIRE 16 -1 (-1000 3525)(-1850 3525);
WIRE 16 -1 (-1000 2125)(-1850 2125);
WIRE 16 -1 (-1000 2725)(-1850 2725);
WIRE 16 -1 (-1000 2325)(-1850 2325);
WIRE 16 -1 (-1000 2925)(-1850 2925);
WIRE 16 -1 (-1000 2175)(-1600 2175);
WIRE 16 -1 (-1000 2975)(-1600 2975);
WIRE 16 -1 (-1000 2375)(-1600 2375);
WIRE 16 -1 (-1000 2575)(-1600 2575);
WIRE 16 -1 (-1000 3375)(-1600 3375);
WIRE 16 -1 (-1000 3175)(-1600 3175);
WIRE 16 -1 (-1000 3575)(-1600 3575);
WIRE 16 -1 (-1000 1350)(-1850 1350);
WIRE 16 -1 (-1000 1600)(-1600 1600);
WIRE 16 -1 (-1000 1150)(-1850 1150);
WIRE 16 -1 (-1000 1200)(-1600 1200);
WIRE 16 -1 (-1000 800)(-1600 800);
WIRE 16 -1 (-1000 200)(-1600 200);
WIRE 16 -1 (-1000 150)(-1850 150);
FORCENOTE
20210527 MODIFY FOR GT
(2200 4375) 0;
DISPLAY LEFT (2200 4375);
DISPLAY 2.510638 (2200 4375);
PAINT PINK (2200 4375);
FORCENOTE
CPU0 PCIE4 TX
(-2225 -475) 0;
DISPLAY LEFT (-2225 -475);
DISPLAY 4.148936 (-2225 -475);
PAINT WHITE (-2225 -475);
FORCENOTE
CPU1 PCIE1 TX
(2350 -475) 0;
DISPLAY LEFT (2350 -475);
DISPLAY 4.148936 (2350 -475);
PAINT WHITE (2350 -475);
QUIT
